FILE_TYPE = MACRO_DRAWING;
SET COLOR_WIRE YELLOW;
SET COLOR_PROP MONO;
SET COLOR_DOT WHITE;
SET COLOR_ARC YELLOW;
SET COLOR_BODY GREEN;
SET COLOR_NOTE MONO;
SET PROP_DISPLAY VALUE;
SET PAGE_NUMBER P204;
FORCEADD OFFPAGE..2
(-1050 4800);
FORCEPROP 2 LAST $XR0 201 
J 0
(-861 4800);
DISPLAY 0.638298 (-861 4800);
PAINT MONO (-861 4800);
FORCEPROP 2 LAST ROOM PVCCIN_CPU0_PWR_VR
J 0
(-1450 4875);
DISPLAY 1.936170 (-1450 4875);
PAINT ORANGE (-1450 4875);
DISPLAY INVISIBLE (-1450 4875);
FORCEPROP 1 LAST COMMENT_BODY TRUE
J 0
(-1095 4705);
DISPLAY 1.723404 (-1095 4705);
PAINT GREEN (-1095 4705);
DISPLAY INVISIBLE (-1095 4705);
FORCEPROP 1 LAST OFFPAGE TRUE
J 0
(-725 4675);
DISPLAY 1.723404 (-725 4675);
PAINT GREEN (-725 4675);
DISPLAY INVISIBLE (-725 4675);
FORCEPROP 2 LAST CDS_LIB mstr_standard
J 2
(-1050 4800);
DISPLAY 1.936170 (-1050 4800);
PAINT ORANGE (-1050 4800);
DISPLAY INVISIBLE (-1050 4800);
FORCEPROP 2 LAST PATH I1
J 0
(-845 4850);
DISPLAY 1.021277 (-845 4850);
PAINT ORANGE (-845 4850);
DISPLAY INVISIBLE (-845 4850);
FORCEPROP 2 LAST BOM_COST PROC_VRD_VCCIN_CPU0
J 0
(-850 4850);
DISPLAY 1.446809 (-850 4850);
PAINT MONO (-850 4850);
DISPLAY INVISIBLE (-850 4850);
FORCEADD RES..1
(-5550 4750);
FORCEPROP 1 LASTPIN (-5650 4750) $PN 1
J 0
(-5638 4762);
DISPLAY 0.617021 (-5638 4762);
PAINT WHITE (-5638 4762);
FORCEPROP 1 LAST TOLERANCE 5%
J 0
(-5600 4650);
DISPLAY 0.617021 (-5600 4650);
PAINT SKYBLUE (-5600 4650);
FORCEPROP 1 LAST LOCATION R6P47
J 0
(-5650 4800);
DISPLAY 0.617021 (-5650 4800);
PAINT AQUA (-5650 4800);
FORCEPROP 1 LASTPIN (-5450 4750) $PN 2
J 0
(-5488 4762);
DISPLAY 0.617021 (-5488 4762);
PAINT WHITE (-5488 4762);
FORCEPROP 1 LAST PART_NUMBER G21497-005
J 0
(-5675 4700);
DISPLAY 0.617021 (-5675 4700);
PAINT BLUE (-5675 4700);
FORCEPROP 1 LAST VALUE 0.0
J 0
(-5700 4650);
DISPLAY 0.617021 (-5700 4650);
PAINT SKYBLUE (-5700 4650);
FORCEPROP 1 LAST PACK_TYPE 0402
J 0
(-5475 4650);
DISPLAY 0.617021 (-5475 4650);
PAINT SKYBLUE (-5475 4650);
FORCEPROP 1 LAST WATTAGE 1/16W
J 0
(-5375 4700);
DISPLAY 0.638298 (-5375 4700);
PAINT SKYBLUE (-5375 4700);
FORCEPROP 1 LAST MATERIAL CHIP
J 0
(-5350 4650);
DISPLAY 0.638298 (-5350 4650);
PAINT SKYBLUE (-5350 4650);
FORCEPROP 0 LAST CDS_SEC 1
J 0
(-5250 4800);
PAINT MONO (-5250 4800);
DISPLAY INVISIBLE (-5250 4800);
FORCEPROP 2 LAST ROOM CPU0
J 0
(-5600 4900);
PAINT PEACH (-5600 4900);
DISPLAY INVISIBLE (-5600 4900);
FORCEPROP 2 LAST SEC 1
J 0
(-5600 4975);
DISPLAY 0.680851 (-5600 4975);
PAINT MONO (-5600 4975);
DISPLAY INVISIBLE (-5600 4975);
FORCEPROP 2 LAST SEC_TYPE 0402
J 0
(-5600 4975);
DISPLAY 1.021277 (-5600 4975);
PAINT ORANGE (-5600 4975);
DISPLAY INVISIBLE (-5600 4975);
FORCEPROP 2 LAST CDS_LIB mstr_discrete
J 0
(-5550 4750);
DISPLAY 1.340426 (-5550 4750);
PAINT ORANGE (-5550 4750);
DISPLAY INVISIBLE (-5550 4750);
FORCEPROP 2 LAST BOM_COST PROC_SIDEBAND
J 0
(-5550 4750);
PAINT MONO (-5550 4750);
DISPLAY INVISIBLE (-5550 4750);
FORCEPROP 1 LAST PATH I103
J 0
(-5600 4900);
DISPLAY 0.978723 (-5600 4900);
PAINT WHITE (-5600 4900);
DISPLAY INVISIBLE (-5600 4900);
FORCEPROP 2 LAST CDS_LOCATION R6P47
J 0
(-6025 4750);
DISPLAY 0.617021 (-6025 4750);
PAINT AQUA (-6025 4750);
DISPLAY INVISIBLE (-6025 4750);
FORCEADD IND-120NH-30-GP..1
R 1
(-1050 3650);
FORCEPROP 2 LAST TYPE IRMS=66A@DELTA_T<40C
J 0
(-1200 3400);
DISPLAY 0.638298 (-1200 3400);
PAINT GREEN (-1200 3400);
FORCEPROP 2 LAST RATED ISAT=94A@25C
J 0
(-1200 3450);
DISPLAY 0.638298 (-1200 3450);
PAINT GREEN (-1200 3450);
FORCEPROP 2 LAST PACK_SIZE DCR=0.17MOHM
J 0
(-1200 3350);
DISPLAY 0.638298 (-1200 3350);
PAINT GREEN (-1200 3350);
FORCEPROP 2 LASTPIN (-900 3625) $PN 2
J 0
(-890 3635);
DISPLAY 0.808511 (-890 3635);
PAINT ORANGE (-890 3635);
FORCEPROP 2 LASTPIN (-1200 3625) $PN 1
J 2
(-1210 3635);
DISPLAY 0.808511 (-1210 3635);
PAINT ORANGE (-1210 3635);
FORCEPROP 1 LAST LOCATION L4C3
J 0
(-1200 3700);
DISPLAY 0.617021 (-1200 3700);
PAINT GREEN (-1200 3700);
FORCEPROP 1 LAST VALUE IND-120NH-30-GP
J 0
(-1200 3550);
DISPLAY 0.617021 (-1200 3550);
PAINT GREEN (-1200 3550);
FORCEPROP 2 LAST ATTRIBUTE 120NH
J 0
(-1200 3500);
DISPLAY 0.638298 (-1200 3500);
PAINT GREEN (-1200 3500);
FORCEPROP 1 LAST PATH I104
R 1
J 0
(-1050 3650);
DISPLAY 0.617021 (-1050 3650);
PAINT GREEN (-1050 3650);
DISPLAY INVISIBLE (-1050 3650);
FORCEPROP 1 LAST PACK_TYPE DISCRET-GB2
R 1
J 0
(-1050 3650);
DISPLAY 0.617021 (-1050 3650);
PAINT GREEN (-1050 3650);
DISPLAY INVISIBLE (-1050 3650);
FORCEPROP 2 LAST SEC 1
J 0
(-1175 3725);
DISPLAY 0.680851 (-1175 3725);
PAINT MONO (-1175 3725);
DISPLAY INVISIBLE (-1175 3725);
FORCEPROP 2 LAST SEC_TYPE DISCRET-GB2
J 0
(-1175 3725);
DISPLAY 1.021277 (-1175 3725);
PAINT ORANGE (-1175 3725);
DISPLAY INVISIBLE (-1175 3725);
FORCEPROP 1 LAST CDS_LMAN_SYM_OUTLINE -75,100,75,-100
R 1
J 0
(-1050 3650);
DISPLAY 0.468085 (-1050 3650);
PAINT GREEN (-1050 3650);
DISPLAY INVISIBLE (-1050 3650);
FORCEPROP 2 LAST CDS_LIB w_hdl
R 1
J 0
(-1050 3650);
PAINT MONO (-1050 3650);
DISPLAY INVISIBLE (-1050 3650);
FORCEPROP 1 LAST PART_NUMBER 068.1202N.M001
R 1
J 0
(-1050 3650);
DISPLAY 0.617021 (-1050 3650);
PAINT GREEN (-1050 3650);
DISPLAY INVISIBLE (-1050 3650);
FORCEADD IND-80NH-1-GP..1
R 1
(-3025 2200);
FORCEPROP 1 LAST VALUE IND-80NH-1-GP
J 0
(-3190 2125);
DISPLAY 0.617021 (-3190 2125);
PAINT GREEN (-3190 2125);
FORCEPROP 2 LAST ATTRIBUTE 80NH
J 0
(-3200 2075);
DISPLAY 0.638298 (-3200 2075);
PAINT GREEN (-3200 2075);
FORCEPROP 1 LAST LOCATION L4C1
J 0
(-3165 2250);
DISPLAY 0.617021 (-3165 2250);
PAINT GREEN (-3165 2250);
FORCEPROP 2 LAST RATED ISAT=50A@25C
J 0
(-3200 2025);
DISPLAY 0.638298 (-3200 2025);
PAINT GREEN (-3200 2025);
FORCEPROP 2 LAST PACK_SIZE DCR=0.22MOHM
J 0
(-3200 1925);
DISPLAY 0.638298 (-3200 1925);
PAINT GREEN (-3200 1925);
FORCEPROP 2 LAST TYPE IRMS=34A@DELTA_T<45C
J 0
(-3200 1975);
DISPLAY 0.638298 (-3200 1975);
PAINT GREEN (-3200 1975);
FORCEPROP 2 LASTPIN (-2875 2175) $PN 2
J 0
(-2865 2185);
DISPLAY 0.808511 (-2865 2185);
PAINT ORANGE (-2865 2185);
FORCEPROP 2 LASTPIN (-3175 2175) $PN 1
J 2
(-3185 2185);
DISPLAY 0.808511 (-3185 2185);
PAINT ORANGE (-3185 2185);
FORCEPROP 1 LAST PACK_TYPE DISCRET-GC2
R 1
J 0
(-3025 2200);
DISPLAY 0.617021 (-3025 2200);
PAINT GREEN (-3025 2200);
DISPLAY INVISIBLE (-3025 2200);
FORCEPROP 2 LAST SEC 1
J 0
(-3175 2175);
DISPLAY 0.680851 (-3175 2175);
PAINT MONO (-3175 2175);
DISPLAY INVISIBLE (-3175 2175);
FORCEPROP 2 LAST SEC_TYPE DISCRET-GC2
J 0
(-3175 2175);
DISPLAY 1.021277 (-3175 2175);
PAINT ORANGE (-3175 2175);
DISPLAY INVISIBLE (-3175 2175);
FORCEPROP 1 LAST CDS_LMAN_SYM_OUTLINE -75,100,75,-100
R 1
J 0
(-3025 2200);
DISPLAY 0.468085 (-3025 2200);
PAINT GREEN (-3025 2200);
DISPLAY INVISIBLE (-3025 2200);
FORCEPROP 2 LAST CDS_LIB w_hdl
R 1
J 0
(-3025 2200);
PAINT MONO (-3025 2200);
DISPLAY INVISIBLE (-3025 2200);
FORCEPROP 1 LAST PART_NUMBER 068.8001N.M001
R 1
J 0
(-3025 2200);
DISPLAY 0.617021 (-3025 2200);
PAINT GREEN (-3025 2200);
DISPLAY INVISIBLE (-3025 2200);
FORCEPROP 1 LAST PATH I105
R 1
J 0
(-3025 2200);
DISPLAY 0.617021 (-3025 2200);
PAINT GREEN (-3025 2200);
DISPLAY INVISIBLE (-3025 2200);
FORCEADD SC1U10V2KX-4-GP..1
(-5200 4150);
FORCEPROP 2 LASTPIN (-5200 4075) $PN 2
R 1
J 2
(-5210 4065);
DISPLAY 0.808511 (-5210 4065);
PAINT ORANGE (-5210 4065);
FORCEPROP 1 LAST LOCATION C4C14
J 0
(-5075 4255);
DISPLAY 0.617021 (-5075 4255);
PAINT GREEN (-5075 4255);
FORCEPROP 1 LAST VALUE SC1U10V2KX-4-GP
R 1
J 0
(-5100 3975);
DISPLAY 0.617021 (-5100 3975);
PAINT GREEN (-5100 3975);
FORCEPROP 2 LASTPIN (-5200 4225) $PN 1
R 1
J 0
(-5210 4235);
DISPLAY 0.808511 (-5210 4235);
PAINT ORANGE (-5210 4235);
FORCEPROP 2 LAST ATTRIBUTE 1UF
J 0
(-5075 4200);
DISPLAY 0.638298 (-5075 4200);
PAINT GREEN (-5075 4200);
FORCEPROP 2 LAST TOLERANCE 10%
J 0
(-5075 4150);
DISPLAY 0.638298 (-5075 4150);
PAINT GREEN (-5075 4150);
FORCEPROP 2 LAST RATED 10V
J 0
(-5075 4100);
DISPLAY 0.638298 (-5075 4100);
PAINT GREEN (-5075 4100);
FORCEPROP 2 LAST PACK_SIZE 0402
J 0
(-5075 4050);
DISPLAY 0.638298 (-5075 4050);
PAINT GREEN (-5075 4050);
FORCEPROP 1 LAST PACK_TYPE SMD-BCG6
J 0
(-5200 4150);
DISPLAY 0.617021 (-5200 4150);
PAINT GREEN (-5200 4150);
DISPLAY INVISIBLE (-5200 4150);
FORCEPROP 2 LAST SEC 1
J 0
(-5175 4225);
DISPLAY 0.680851 (-5175 4225);
PAINT MONO (-5175 4225);
DISPLAY INVISIBLE (-5175 4225);
FORCEPROP 2 LAST SEC_TYPE SMD-BCG6
J 0
(-5175 4225);
DISPLAY 1.021277 (-5175 4225);
PAINT ORANGE (-5175 4225);
DISPLAY INVISIBLE (-5175 4225);
FORCEPROP 1 LAST PART_NUMBER 78.10523.8FL
J 0
(-5200 4150);
DISPLAY 0.617021 (-5200 4150);
PAINT GREEN (-5200 4150);
DISPLAY INVISIBLE (-5200 4150);
FORCEPROP 2 LAST CDS_LIB w_hdl
J 0
(-5200 4150);
PAINT MONO (-5200 4150);
DISPLAY INVISIBLE (-5200 4150);
FORCEPROP 1 LAST PATH I113
J 0
(-5200 4150);
DISPLAY 0.617021 (-5200 4150);
PAINT GREEN (-5200 4150);
DISPLAY INVISIBLE (-5200 4150);
FORCEPROP 1 LAST CDS_LMAN_SYM_OUTLINE -50,25,50,-25
J 0
(-5200 4150);
DISPLAY 0.468085 (-5200 4150);
PAINT GREEN (-5200 4150);
DISPLAY INVISIBLE (-5200 4150);
FORCEADD 1R3F-GP..1
(-1975 3175);
FORCEPROP 0 LAST POP NOPOP
J 0
(-1925 3000);
DISPLAY 0.638298 (-1925 3000);
PAINT RED (-1925 3000);
FORCEPROP 2 LAST PACK_SIZE 0603
J 0
(-1925 3050);
DISPLAY 0.638298 (-1925 3050);
PAINT GREEN (-1925 3050);
FORCEPROP 2 LAST RATED 1/10W
J 0
(-1925 3100);
DISPLAY 0.638298 (-1925 3100);
PAINT GREEN (-1925 3100);
FORCEPROP 1 LAST LOCATION RT24
J 0
(-1925 3300);
DISPLAY 0.617021 (-1925 3300);
PAINT GREEN (-1925 3300);
FORCEPROP 2 LAST ATTRIBUTE 1 OHM
J 0
(-1925 3200);
DISPLAY 0.638298 (-1925 3200);
PAINT GREEN (-1925 3200);
FORCEPROP 2 LASTPIN (-1975 3050) $PN 2
R 1
J 2
(-1985 3040);
DISPLAY 0.808511 (-1985 3040);
PAINT ORANGE (-1985 3040);
FORCEPROP 2 LASTPIN (-1975 3300) $PN 1
R 1
J 0
(-1985 3310);
DISPLAY 0.808511 (-1985 3310);
PAINT ORANGE (-1985 3310);
FORCEPROP 2 LAST TOLERANCE 1%
J 0
(-1925 3150);
DISPLAY 0.638298 (-1925 3150);
PAINT GREEN (-1925 3150);
FORCEPROP 1 LAST VALUE 1R3F-GP
J 0
(-1925 3250);
DISPLAY 0.617021 (-1925 3250);
PAINT GREEN (-1925 3250);
FORCEPROP 1 LAST PACK_TYPE RCL_GP
J 0
(-1975 3175);
DISPLAY 0.617021 (-1975 3175);
PAINT GREEN (-1975 3175);
DISPLAY INVISIBLE (-1975 3175);
FORCEPROP 2 LAST SEC 1
J 0
(-1925 3275);
DISPLAY 0.680851 (-1925 3275);
PAINT MONO (-1925 3275);
DISPLAY INVISIBLE (-1925 3275);
FORCEPROP 2 LAST SEC_TYPE RCL_GP
J 0
(-1925 3275);
DISPLAY 1.021277 (-1925 3275);
PAINT ORANGE (-1925 3275);
DISPLAY INVISIBLE (-1925 3275);
FORCEPROP 1 LAST PART_NUMBER 64.1R005.55L
J 0
(-1975 3175);
DISPLAY 0.617021 (-1975 3175);
PAINT GREEN (-1975 3175);
DISPLAY INVISIBLE (-1975 3175);
FORCEPROP 2 LAST CDS_LIB w_hdl
J 0
(-1975 3175);
DISPLAY INVISIBLE (-1975 3175);
FORCEPROP 1 LAST CDS_LMAN_SYM_OUTLINE -50,75,50,-75
J 0
(-1975 3175);
DISPLAY 0.468085 (-1975 3175);
PAINT GREEN (-1975 3175);
DISPLAY INVISIBLE (-1975 3175);
FORCEPROP 1 LAST PATH I114
J 0
(-1975 3175);
DISPLAY 0.617021 (-1975 3175);
PAINT GREEN (-1975 3175);
DISPLAY INVISIBLE (-1975 3175);
FORCEADD GND..1
(-2475 3275);
FORCEPROP 3 LASTPIN (-2475 3325) SIG_NAME GND\g
J 0
(-2465 3335);
DISPLAY 0.659574 (-2465 3335);
PAINT MONO (-2465 3335);
DISPLAY INVISIBLE (-2465 3335);
FORCEPROP 2 LAST ROOM PVCCIN_CPU0_PWR_VR
J 0
(-3025 3350);
DISPLAY 1.936170 (-3025 3350);
PAINT ORANGE (-3025 3350);
DISPLAY INVISIBLE (-3025 3350);
FORCEPROP 2 LAST BOM_COST PROC_VRD_VCCIN_CPU0
J 0
(-2850 3350);
DISPLAY 1.446809 (-2850 3350);
PAINT MONO (-2850 3350);
DISPLAY INVISIBLE (-2850 3350);
FORCEPROP 1 LAST BODY_TYPE PLUMBING
J 0
(-2520 3232);
DISPLAY 0.340426 (-2520 3232);
PAINT GREEN (-2520 3232);
DISPLAY INVISIBLE (-2520 3232);
FORCEPROP 1 LAST SIZE 1B
J 0
(-2400 3225);
DISPLAY 1.723404 (-2400 3225);
PAINT GREEN (-2400 3225);
DISPLAY INVISIBLE (-2400 3225);
FORCEPROP 1 LAST PATH I13
J 0
(-2400 3275);
DISPLAY 0.872340 (-2400 3275);
PAINT AQUA (-2400 3275);
DISPLAY INVISIBLE (-2400 3275);
FORCEPROP 2 LAST CDS_LIB mstr_symbols
J 0
(-2475 3275);
DISPLAY 1.936170 (-2475 3275);
PAINT ORANGE (-2475 3275);
DISPLAY INVISIBLE (-2475 3275);
FORCEPROP 1 LAST VOLTAGE 0
J 0
(-2475 3275);
PAINT SKYBLUE (-2475 3275);
DISPLAY INVISIBLE (-2475 3275);
FORCEPROP 1 LAST HDL_POWER GND
J 0
(-2475 3425);
DISPLAY 1.723404 (-2475 3425);
PAINT GREEN (-2475 3425);
DISPLAY INVISIBLE (-2475 3425);
FORCEADD CAP..1
(-4875 4200);
FORCEPROP 1 LAST MATERIAL X7R
J 0
(-4825 4100);
DISPLAY 0.617021 (-4825 4100);
PAINT SKYBLUE (-4825 4100);
FORCEPROP 1 LASTPIN (-4875 4100) $PN 2
J 0
(-4865 4080);
DISPLAY 0.617021 (-4865 4080);
PAINT ORANGE (-4865 4080);
FORCEPROP 1 LAST TOLERANCE 10%
J 0
(-4825 4150);
DISPLAY 0.617021 (-4825 4150);
PAINT SKYBLUE (-4825 4150);
FORCEPROP 1 LAST PART_NUMBER A36096-155
J 0
(-4825 4050);
DISPLAY 0.617021 (-4825 4050);
PAINT BLUE (-4825 4050);
FORCEPROP 1 LASTPIN (-4875 4300) $PN 1
J 0
(-4865 4280);
DISPLAY 0.617021 (-4865 4280);
PAINT ORANGE (-4865 4280);
FORCEPROP 1 LAST PACK_TYPE 0402
J 0
(-4825 4000);
DISPLAY 0.617021 (-4825 4000);
PAINT SKYBLUE (-4825 4000);
FORCEPROP 1 LAST VOLTAGE 16V
J 0
(-4825 4200);
DISPLAY 0.617021 (-4825 4200);
PAINT SKYBLUE (-4825 4200);
FORCEPROP 1 LAST VALUE 0.22UF
J 0
(-4825 4250);
DISPLAY 0.617021 (-4825 4250);
PAINT SKYBLUE (-4825 4250);
FORCEPROP 1 LAST LOCATION C4D47
J 0
(-4825 4300);
DISPLAY 0.617021 (-4825 4300);
PAINT AQUA (-4825 4300);
FORCEPROP 2 LAST SEC 1
J 0
(-4825 4400);
DISPLAY 0.680851 (-4825 4400);
PAINT MONO (-4825 4400);
DISPLAY INVISIBLE (-4825 4400);
FORCEPROP 1 LAST PATH I18
J 0
(-4825 4350);
DISPLAY 0.978723 (-4825 4350);
PAINT WHITE (-4825 4350);
DISPLAY INVISIBLE (-4825 4350);
FORCEPROP 2 LAST ROOM PVCCIN_CPU0_PWR_VR
J 0
(-4825 4350);
DISPLAY 1.361702 (-4825 4350);
PAINT ORANGE (-4825 4350);
DISPLAY INVISIBLE (-4825 4350);
FORCEPROP 2 LAST SEC_TYPE 0402
J 0
(-4825 4400);
DISPLAY 1.021277 (-4825 4400);
PAINT ORANGE (-4825 4400);
DISPLAY INVISIBLE (-4825 4400);
FORCEPROP 2 LAST CDS_LIB mstr_discrete
J 0
(-4875 4200);
PAINT ORANGE (-4875 4200);
DISPLAY INVISIBLE (-4875 4200);
FORCEADD OFFPAGE..2
(-1075 4475);
FORCEPROP 2 LAST $XR0 201 
J 0
(-886 4475);
DISPLAY 0.638298 (-886 4475);
PAINT MONO (-886 4475);
FORCEPROP 2 LAST ROOM PVCCIN_CPU0_PWR_VR
J 0
(-1475 4550);
DISPLAY 1.936170 (-1475 4550);
PAINT ORANGE (-1475 4550);
DISPLAY INVISIBLE (-1475 4550);
FORCEPROP 1 LAST COMMENT_BODY TRUE
J 0
(-1120 4380);
DISPLAY 1.723404 (-1120 4380);
PAINT GREEN (-1120 4380);
DISPLAY INVISIBLE (-1120 4380);
FORCEPROP 2 LAST CDS_LIB mstr_standard
J 0
(-1075 4475);
DISPLAY 1.936170 (-1075 4475);
PAINT ORANGE (-1075 4475);
DISPLAY INVISIBLE (-1075 4475);
FORCEPROP 2 LAST PATH I2
J 0
(-870 4525);
DISPLAY 1.021277 (-870 4525);
PAINT ORANGE (-870 4525);
DISPLAY INVISIBLE (-870 4525);
FORCEPROP 1 LAST OFFPAGE TRUE
J 0
(-750 4350);
DISPLAY 1.723404 (-750 4350);
PAINT GREEN (-750 4350);
DISPLAY INVISIBLE (-750 4350);
FORCEPROP 2 LAST BOM_COST PROC_VRD_VCCIN_CPU0
J 0
(-875 4525);
DISPLAY 1.446809 (-875 4525);
PAINT MONO (-875 4525);
DISPLAY INVISIBLE (-875 4525);
FORCEADD CAP..1
R 2
(-5825 3575);
FORCEPROP 1 LASTPIN (-5825 3675) $PN 1
J 2
(-5835 3655);
DISPLAY 0.617021 (-5835 3655);
PAINT ORANGE (-5835 3655);
FORCEPROP 1 LAST LOCATION C4C17
J 2
(-5875 3675);
DISPLAY 0.617021 (-5875 3675);
PAINT AQUA (-5875 3675);
FORCEPROP 1 LAST TOLERANCE 10%
J 2
(-5875 3525);
DISPLAY 0.617021 (-5875 3525);
PAINT SKYBLUE (-5875 3525);
FORCEPROP 1 LAST VALUE 0.220UF
J 2
(-5875 3625);
DISPLAY 0.617021 (-5875 3625);
PAINT SKYBLUE (-5875 3625);
FORCEPROP 1 LASTPIN (-5825 3475) $PN 2
J 2
(-5835 3455);
DISPLAY 0.617021 (-5835 3455);
PAINT ORANGE (-5835 3455);
FORCEPROP 1 LAST VOLTAGE 16V
J 2
(-5875 3575);
DISPLAY 0.617021 (-5875 3575);
PAINT SKYBLUE (-5875 3575);
FORCEPROP 1 LAST MATERIAL X7R
J 2
(-5875 3475);
DISPLAY 0.617021 (-5875 3475);
PAINT SKYBLUE (-5875 3475);
FORCEPROP 1 LAST PART_NUMBER A36096-104
J 2
(-5875 3425);
DISPLAY 0.617021 (-5875 3425);
PAINT BLUE (-5875 3425);
FORCEPROP 1 LAST PACK_TYPE 0402
J 2
(-5875 3375);
DISPLAY 0.617021 (-5875 3375);
PAINT SKYBLUE (-5875 3375);
FORCEPROP 2 LAST NO_XNET_CONNECTION 1
J 0
(-5875 3775);
PAINT MONO (-5875 3775);
DISPLAY INVISIBLE (-5875 3775);
FORCEPROP 2 LAST SEC_TYPE 0402
J 0
(-5875 3775);
DISPLAY 1.021277 (-5875 3775);
PAINT ORANGE (-5875 3775);
DISPLAY INVISIBLE (-5875 3775);
FORCEPROP 0 LAST SPOF TRUE
J 0
(-5875 3775);
DISPLAY 1.021277 (-5875 3775);
PAINT ORANGE (-5875 3775);
DISPLAY INVISIBLE (-5875 3775);
FORCEPROP 2 LAST CDS_LIB mstr_discrete
J 0
(-5825 3575);
PAINT ORANGE (-5825 3575);
DISPLAY INVISIBLE (-5825 3575);
FORCEPROP 2 LAST SEC 1
J 0
(-5875 3775);
DISPLAY 0.680851 (-5875 3775);
PAINT MONO (-5875 3775);
DISPLAY INVISIBLE (-5875 3775);
FORCEPROP 2 LAST CDS_LOCATION C4C17
J 2
(-5875 3675);
DISPLAY 0.617021 (-5875 3675);
PAINT AQUA (-5875 3675);
DISPLAY INVISIBLE (-5875 3675);
FORCEPROP 1 LAST PATH I22
J 2
(-5875 3725);
DISPLAY 0.978723 (-5875 3725);
PAINT WHITE (-5875 3725);
DISPLAY INVISIBLE (-5875 3725);
FORCEPROP 2 LAST ROOM PVCCIN_CPU0_PWR_VR
J 0
(-5900 3725);
DISPLAY 1.361702 (-5900 3725);
PAINT ORANGE (-5900 3725);
DISPLAY INVISIBLE (-5900 3725);
FORCEADD OFFPAGE..2
(-1500 4125);
FORCEPROP 2 LAST $XR2 201 
J 0
(-1071 4125);
DISPLAY 0.638298 (-1071 4125);
PAINT MONO (-1071 4125);
FORCEPROP 2 LAST $XR1 203 
J 0
(-1191 4125);
DISPLAY 0.638298 (-1191 4125);
PAINT MONO (-1191 4125);
FORCEPROP 2 LAST $XR0 202 
J 0
(-1311 4125);
DISPLAY 0.638298 (-1311 4125);
PAINT MONO (-1311 4125);
FORCEPROP 2 LAST BOM_COST PROC_VRD_VCCIN_CPU0
J 0
(-1300 4175);
DISPLAY 1.446809 (-1300 4175);
PAINT MONO (-1300 4175);
DISPLAY INVISIBLE (-1300 4175);
FORCEPROP 1 LAST OFFPAGE TRUE
J 0
(-1175 4000);
DISPLAY 1.723404 (-1175 4000);
PAINT GREEN (-1175 4000);
DISPLAY INVISIBLE (-1175 4000);
FORCEPROP 2 LAST PATH I3
J 0
(-1320 4200);
DISPLAY 1.021277 (-1320 4200);
PAINT ORANGE (-1320 4200);
DISPLAY INVISIBLE (-1320 4200);
FORCEPROP 2 LAST CDS_LIB mstr_standard
J 0
(-1500 4125);
PAINT ORANGE (-1500 4125);
DISPLAY INVISIBLE (-1500 4125);
FORCEPROP 1 LAST COMMENT_BODY TRUE
J 0
(-1545 4030);
DISPLAY 1.723404 (-1545 4030);
PAINT GREEN (-1545 4030);
DISPLAY INVISIBLE (-1545 4030);
FORCEPROP 2 LAST ROOM PVCCIN_CPU0_PWR_VR
J 0
(-1900 4200);
DISPLAY 1.936170 (-1900 4200);
PAINT ORANGE (-1900 4200);
DISPLAY INVISIBLE (-1900 4200);
FORCEADD CAP..1
(-5700 4175);
FORCEPROP 1 LASTPIN (-5700 4275) $PN 1
J 0
(-5690 4255);
DISPLAY 0.617021 (-5690 4255);
PAINT ORANGE (-5690 4255);
FORCEPROP 1 LAST MATERIAL X6S
J 0
(-5650 4075);
DISPLAY 0.617021 (-5650 4075);
PAINT SKYBLUE (-5650 4075);
FORCEPROP 1 LAST TOLERANCE 10%
J 0
(-5650 4125);
DISPLAY 0.617021 (-5650 4125);
PAINT SKYBLUE (-5650 4125);
FORCEPROP 1 LAST LOCATION C4D46
J 0
(-5650 4275);
DISPLAY 0.617021 (-5650 4275);
PAINT AQUA (-5650 4275);
FORCEPROP 1 LASTPIN (-5700 4075) $PN 2
J 0
(-5690 4055);
DISPLAY 0.617021 (-5690 4055);
PAINT ORANGE (-5690 4055);
FORCEPROP 1 LAST PART_NUMBER D97712-011
J 0
(-5650 4025);
DISPLAY 0.617021 (-5650 4025);
PAINT BLUE (-5650 4025);
FORCEPROP 1 LAST PACK_TYPE 0402
J 0
(-5650 3975);
DISPLAY 0.617021 (-5650 3975);
PAINT SKYBLUE (-5650 3975);
FORCEPROP 1 LAST VALUE 1.0UF
J 0
(-5650 4225);
DISPLAY 0.617021 (-5650 4225);
PAINT SKYBLUE (-5650 4225);
FORCEPROP 1 LAST VOLTAGE 16V
J 0
(-5650 4175);
DISPLAY 0.617021 (-5650 4175);
PAINT SKYBLUE (-5650 4175);
FORCEPROP 2 LAST CDS_LIB mstr_discrete
J 0
(-5700 4175);
PAINT ORANGE (-5700 4175);
DISPLAY INVISIBLE (-5700 4175);
FORCEPROP 2 LAST ROOM PVCCIN_CPU0_PWR_VR
J 0
(-5650 4325);
DISPLAY 1.361702 (-5650 4325);
PAINT ORANGE (-5650 4325);
DISPLAY INVISIBLE (-5650 4325);
FORCEPROP 1 LAST PATH I34
J 0
(-5650 4325);
DISPLAY 0.978723 (-5650 4325);
PAINT WHITE (-5650 4325);
DISPLAY INVISIBLE (-5650 4325);
FORCEPROP 2 LAST SEC 1
J 0
(-5650 4375);
DISPLAY 0.680851 (-5650 4375);
PAINT MONO (-5650 4375);
DISPLAY INVISIBLE (-5650 4375);
FORCEPROP 2 LAST SEC_TYPE 0402
J 0
(-5650 4375);
DISPLAY 1.021277 (-5650 4375);
PAINT ORANGE (-5650 4375);
DISPLAY INVISIBLE (-5650 4375);
FORCEADD CAP_A..1
(-6000 4175);
FORCEPROP 1 LAST TOLERANCE 10%
J 0
(-5950 4125);
DISPLAY 0.617021 (-5950 4125);
PAINT SKYBLUE (-5950 4125);
FORCEPROP 1 LAST PACK_TYPE 0402V
J 0
(-5950 3975);
DISPLAY 0.617021 (-5950 3975);
PAINT SKYBLUE (-5950 3975);
FORCEPROP 1 LAST PART_NUMBER A36096-030
J 0
(-5950 4025);
DISPLAY 0.617021 (-5950 4025);
PAINT BLUE (-5950 4025);
FORCEPROP 1 LASTPIN (-6000 4075) $PN 2
J 0
(-5990 4055);
DISPLAY 0.617021 (-5990 4055);
PAINT ORANGE (-5990 4055);
FORCEPROP 1 LAST MATERIAL X7R
J 0
(-5950 4075);
DISPLAY 0.617021 (-5950 4075);
PAINT SKYBLUE (-5950 4075);
FORCEPROP 1 LAST VALUE 0.1UF
J 0
(-5950 4225);
DISPLAY 0.617021 (-5950 4225);
PAINT SKYBLUE (-5950 4225);
FORCEPROP 1 LAST VOLTAGE 16V
J 0
(-5950 4175);
DISPLAY 0.617021 (-5950 4175);
PAINT SKYBLUE (-5950 4175);
FORCEPROP 1 LASTPIN (-6000 4275) $PN 1
J 0
(-5990 4255);
DISPLAY 0.617021 (-5990 4255);
PAINT ORANGE (-5990 4255);
FORCEPROP 1 LAST LOCATION C4C19
J 0
(-5950 4275);
DISPLAY 0.617021 (-5950 4275);
PAINT AQUA (-5950 4275);
FORCEPROP 2 LAST CDS_LIB dev_discrete
J 0
(-6000 4175);
PAINT ORANGE (-6000 4175);
DISPLAY INVISIBLE (-6000 4175);
FORCEPROP 2 LAST SEC 1
J 0
(-5950 4375);
DISPLAY 0.680851 (-5950 4375);
PAINT MONO (-5950 4375);
DISPLAY INVISIBLE (-5950 4375);
FORCEPROP 2 LAST SEC_TYPE 0402V
J 0
(-5950 4375);
DISPLAY 1.021277 (-5950 4375);
PAINT ORANGE (-5950 4375);
DISPLAY INVISIBLE (-5950 4375);
FORCEPROP 2 LAST CDS_SEC 1
J 0
(-5950 4325);
PAINT ORANGE (-5950 4325);
DISPLAY INVISIBLE (-5950 4325);
FORCEPROP 2 LAST ROOM PVCCIN_CPU0_PWR_VR
J 0
(-5950 4325);
DISPLAY 1.361702 (-5950 4325);
PAINT ORANGE (-5950 4325);
DISPLAY INVISIBLE (-5950 4325);
FORCEPROP 1 LAST PATH I35
J 0
(-5950 4325);
DISPLAY 0.978723 (-5950 4325);
PAINT WHITE (-5950 4325);
DISPLAY INVISIBLE (-5950 4325);
FORCEADD CAP..1
(-6300 4175);
FORCEPROP 1 LAST PART_NUMBER D97712-011
J 0
(-6250 4025);
DISPLAY 0.617021 (-6250 4025);
PAINT BLUE (-6250 4025);
FORCEPROP 1 LASTPIN (-6300 4075) $PN 2
J 0
(-6290 4055);
DISPLAY 0.617021 (-6290 4055);
PAINT ORANGE (-6290 4055);
FORCEPROP 1 LAST PACK_TYPE 0402
J 0
(-6250 3975);
DISPLAY 0.617021 (-6250 3975);
PAINT SKYBLUE (-6250 3975);
FORCEPROP 1 LAST MATERIAL X6S
J 0
(-6250 4075);
DISPLAY 0.617021 (-6250 4075);
PAINT SKYBLUE (-6250 4075);
FORCEPROP 1 LAST LOCATION C4C18
J 0
(-6250 4275);
DISPLAY 0.617021 (-6250 4275);
PAINT AQUA (-6250 4275);
FORCEPROP 1 LAST VALUE 1.0UF
J 0
(-6250 4225);
DISPLAY 0.617021 (-6250 4225);
PAINT SKYBLUE (-6250 4225);
FORCEPROP 1 LASTPIN (-6300 4275) $PN 1
J 0
(-6290 4255);
DISPLAY 0.617021 (-6290 4255);
PAINT ORANGE (-6290 4255);
FORCEPROP 1 LAST VOLTAGE 16V
J 0
(-6250 4175);
DISPLAY 0.617021 (-6250 4175);
PAINT SKYBLUE (-6250 4175);
FORCEPROP 1 LAST TOLERANCE 10%
J 0
(-6250 4125);
DISPLAY 0.617021 (-6250 4125);
PAINT SKYBLUE (-6250 4125);
FORCEPROP 2 LAST SEC_TYPE 0402
J 0
(-6250 4375);
DISPLAY 1.021277 (-6250 4375);
PAINT ORANGE (-6250 4375);
DISPLAY INVISIBLE (-6250 4375);
FORCEPROP 2 LAST SEC 1
J 0
(-6250 4375);
DISPLAY 0.680851 (-6250 4375);
PAINT MONO (-6250 4375);
DISPLAY INVISIBLE (-6250 4375);
FORCEPROP 1 LAST PATH I36
J 0
(-6250 4325);
DISPLAY 0.978723 (-6250 4325);
PAINT WHITE (-6250 4325);
DISPLAY INVISIBLE (-6250 4325);
FORCEPROP 2 LAST ROOM PVCCIN_CPU0_PWR_VR
J 0
(-6250 4325);
DISPLAY 1.361702 (-6250 4325);
PAINT ORANGE (-6250 4325);
DISPLAY INVISIBLE (-6250 4325);
FORCEPROP 2 LAST CDS_LIB mstr_discrete
J 0
(-6300 4175);
PAINT ORANGE (-6300 4175);
DISPLAY INVISIBLE (-6300 4175);
FORCEADD CAP..1
(-6600 4175);
FORCEPROP 1 LAST PART_NUMBER C95333-007
J 0
(-6550 4025);
DISPLAY 0.617021 (-6550 4025);
PAINT BLUE (-6550 4025);
FORCEPROP 1 LAST TOLERANCE 10%
J 0
(-6550 4125);
DISPLAY 0.617021 (-6550 4125);
PAINT SKYBLUE (-6550 4125);
FORCEPROP 1 LASTPIN (-6600 4075) $PN 2
J 0
(-6590 4055);
DISPLAY 0.617021 (-6590 4055);
PAINT ORANGE (-6590 4055);
FORCEPROP 1 LAST LOCATION C6N10
J 0
(-6550 4275);
DISPLAY 0.617021 (-6550 4275);
PAINT AQUA (-6550 4275);
FORCEPROP 1 LAST VOLTAGE 16V
J 0
(-6550 4175);
DISPLAY 0.617021 (-6550 4175);
PAINT SKYBLUE (-6550 4175);
FORCEPROP 1 LAST PACK_TYPE 0805
J 0
(-6550 3975);
DISPLAY 0.617021 (-6550 3975);
PAINT SKYBLUE (-6550 3975);
FORCEPROP 1 LAST VALUE 10UF
J 0
(-6550 4225);
DISPLAY 0.617021 (-6550 4225);
PAINT SKYBLUE (-6550 4225);
FORCEPROP 1 LAST MATERIAL X6S
J 0
(-6550 4075);
DISPLAY 0.617021 (-6550 4075);
PAINT SKYBLUE (-6550 4075);
FORCEPROP 1 LASTPIN (-6600 4275) $PN 1
J 0
(-6590 4255);
DISPLAY 0.617021 (-6590 4255);
PAINT ORANGE (-6590 4255);
FORCEPROP 2 LAST SEC_TYPE 0805
J 0
(-6550 4375);
DISPLAY 1.021277 (-6550 4375);
PAINT ORANGE (-6550 4375);
DISPLAY INVISIBLE (-6550 4375);
FORCEPROP 2 LAST SEC 1
J 0
(-6550 4375);
DISPLAY 0.680851 (-6550 4375);
PAINT MONO (-6550 4375);
DISPLAY INVISIBLE (-6550 4375);
FORCEPROP 1 LAST PATH I37
J 0
(-6550 4325);
DISPLAY 0.978723 (-6550 4325);
PAINT WHITE (-6550 4325);
DISPLAY INVISIBLE (-6550 4325);
FORCEPROP 2 LAST ROOM PVCCIN_CPU0_PWR_VR
J 0
(-6550 4325);
DISPLAY 1.361702 (-6550 4325);
PAINT ORANGE (-6550 4325);
DISPLAY INVISIBLE (-6550 4325);
FORCEPROP 2 LAST CDS_LIB mstr_discrete
J 0
(-6600 4175);
PAINT ORANGE (-6600 4175);
DISPLAY INVISIBLE (-6600 4175);
FORCEADD CAP..1
(-6900 4175);
FORCEPROP 1 LAST TOLERANCE 10%
J 0
(-6850 4125);
DISPLAY 0.617021 (-6850 4125);
PAINT SKYBLUE (-6850 4125);
FORCEPROP 1 LAST LOCATION C6P17
J 0
(-6850 4275);
DISPLAY 0.617021 (-6850 4275);
PAINT AQUA (-6850 4275);
FORCEPROP 1 LAST VALUE 10UF
J 0
(-6850 4225);
DISPLAY 0.617021 (-6850 4225);
PAINT SKYBLUE (-6850 4225);
FORCEPROP 1 LAST VOLTAGE 16V
J 0
(-6850 4175);
DISPLAY 0.617021 (-6850 4175);
PAINT SKYBLUE (-6850 4175);
FORCEPROP 1 LAST PACK_TYPE 0805
J 0
(-6850 3975);
DISPLAY 0.617021 (-6850 3975);
PAINT SKYBLUE (-6850 3975);
FORCEPROP 1 LAST PART_NUMBER C95333-007
J 0
(-6850 4025);
DISPLAY 0.617021 (-6850 4025);
PAINT BLUE (-6850 4025);
FORCEPROP 1 LAST MATERIAL X6S
J 0
(-6850 4075);
DISPLAY 0.617021 (-6850 4075);
PAINT SKYBLUE (-6850 4075);
FORCEPROP 1 LASTPIN (-6900 4275) $PN 1
J 0
(-6890 4255);
DISPLAY 0.617021 (-6890 4255);
PAINT ORANGE (-6890 4255);
FORCEPROP 1 LASTPIN (-6900 4075) $PN 2
J 0
(-6890 4055);
DISPLAY 0.617021 (-6890 4055);
PAINT ORANGE (-6890 4055);
FORCEPROP 2 LAST CDS_LIB mstr_discrete
J 0
(-6900 4175);
PAINT ORANGE (-6900 4175);
DISPLAY INVISIBLE (-6900 4175);
FORCEPROP 2 LAST CDS_LOCATION C6P17
J 0
(-6850 4275);
DISPLAY 0.617021 (-6850 4275);
PAINT AQUA (-6850 4275);
DISPLAY INVISIBLE (-6850 4275);
FORCEPROP 2 LAST ROOM PVCCIN_CPU0_PWR_VR
J 0
(-6850 4325);
DISPLAY 1.361702 (-6850 4325);
PAINT ORANGE (-6850 4325);
DISPLAY INVISIBLE (-6850 4325);
FORCEPROP 1 LAST PATH I38
J 0
(-6850 4325);
DISPLAY 0.978723 (-6850 4325);
PAINT WHITE (-6850 4325);
DISPLAY INVISIBLE (-6850 4325);
FORCEPROP 2 LAST SEC_TYPE 0805
J 0
(-6850 4375);
DISPLAY 1.021277 (-6850 4375);
PAINT ORANGE (-6850 4375);
DISPLAY INVISIBLE (-6850 4375);
FORCEPROP 2 LAST SEC 1
J 0
(-6850 4375);
DISPLAY 0.680851 (-6850 4375);
PAINT MONO (-6850 4375);
DISPLAY INVISIBLE (-6850 4375);
FORCEADD PVCCIN_CPU0..1
(-400 3725);
FORCEPROP 3 LASTPIN (-400 3675) SIG_NAME PVCCIN_CPU0\g
J 0
(-390 3685);
DISPLAY 0.659574 (-390 3685);
PAINT MONO (-390 3685);
DISPLAY INVISIBLE (-390 3685);
FORCEPROP 1 LAST BODY_TYPE PLUMBING
J 0
(-445 3682);
DISPLAY 0.340426 (-445 3682);
PAINT GREEN (-445 3682);
DISPLAY INVISIBLE (-445 3682);
FORCEPROP 1 LAST VOLTAGE 2.0V
J 0
(-445 3682);
DISPLAY 0.340426 (-445 3682);
PAINT SKYBLUE (-445 3682);
DISPLAY INVISIBLE (-445 3682);
FORCEPROP 2 LAST CDS_LIB mstr_symbols
J 0
(-400 3725);
PAINT ORANGE (-400 3725);
DISPLAY INVISIBLE (-400 3725);
FORCEPROP 1 LAST PATH I4
J 0
(-350 3750);
DISPLAY 0.872340 (-350 3750);
PAINT AQUA (-350 3750);
DISPLAY INVISIBLE (-350 3750);
FORCEPROP 1 LAST HDL_POWER PVCCIN_CPU0
J 1
(-400 3775);
DISPLAY 0.872340 (-400 3775);
PAINT GREEN (-400 3775);
DISPLAY INVISIBLE (-400 3775);
FORCEADD OFFPAGE..1
(-6450 3825);
FORCEPROP 2 LASTPIN (-6400 3825) SIG_NAME VR_PVCCIN_CPU0_PWM5
J 0
(-6385 3835);
DISPLAY 0.617021 (-6385 3835);
PAINT ORANGE (-6385 3835);
FORCEPROP 2 LAST $XR0 201 
J 0
(-6732 3825);
DISPLAY 0.638298 (-6732 3825);
PAINT MONO (-6732 3825);
FORCEPROP 2 LAST ROOM PVCCIN_CPU0_PWR_VR
J 0
(-6850 3900);
DISPLAY 1.936170 (-6850 3900);
PAINT ORANGE (-6850 3900);
DISPLAY INVISIBLE (-6850 3900);
FORCEPROP 1 LAST COMMENT_BODY TRUE
J 0
(-6325 3725);
DISPLAY 1.680851 (-6325 3725);
PAINT GREEN (-6325 3725);
DISPLAY INVISIBLE (-6325 3725);
FORCEPROP 2 LAST BOM_COST PROC_VRD_VCCIN_CPU0
J 0
(-6700 3875);
DISPLAY 1.446809 (-6700 3875);
PAINT MONO (-6700 3875);
DISPLAY INVISIBLE (-6700 3875);
FORCEPROP 2 LAST PATH I40
J 0
(-6720 3875);
DISPLAY 1.021277 (-6720 3875);
PAINT ORANGE (-6720 3875);
DISPLAY INVISIBLE (-6720 3875);
FORCEPROP 2 LAST CDS_LIB mstr_standard
J 0
(-6450 3825);
DISPLAY 1.936170 (-6450 3825);
PAINT ORANGE (-6450 3825);
DISPLAY INVISIBLE (-6450 3825);
FORCEPROP 1 LAST OFFPAGE TRUE
J 0
(-6125 3700);
DISPLAY 1.680851 (-6125 3700);
PAINT GREEN (-6125 3700);
DISPLAY INVISIBLE (-6125 3700);
FORCEADD VCC_CORE..1
(-6675 4650);
FORCEPROP 3 LASTPIN (-6675 4600) SIG_NAME VR_FET_SW_P12V_STBY_PVCCIN_CPU0\g
J 0
(-6665 4610);
DISPLAY 0.659574 (-6665 4610);
PAINT MONO (-6665 4610);
DISPLAY INVISIBLE (-6665 4610);
FORCEPROP 1 LAST HDL_POWER VR_FET_SW_P12V_STBY_PVCCIN_CPU0
J 1
(-6600 4700);
DISPLAY 0.617021 (-6600 4700);
PAINT GREEN (-6600 4700);
FORCEPROP 2 LAST CDS_LIB mstr_symbols
J 0
(-6675 4650);
DISPLAY 1.936170 (-6675 4650);
PAINT ORANGE (-6675 4650);
DISPLAY INVISIBLE (-6675 4650);
FORCEPROP 1 LAST PATH I41
J 0
(-6625 4675);
DISPLAY 0.872340 (-6625 4675);
PAINT AQUA (-6625 4675);
DISPLAY INVISIBLE (-6625 4675);
FORCEADD CAP..1
(-7200 4175);
FORCEPROP 1 LAST PACK_TYPE 0805
J 0
(-7150 3975);
DISPLAY 0.617021 (-7150 3975);
PAINT SKYBLUE (-7150 3975);
FORCEPROP 1 LAST PART_NUMBER C95333-007
J 0
(-7150 4025);
DISPLAY 0.617021 (-7150 4025);
PAINT BLUE (-7150 4025);
FORCEPROP 1 LAST MATERIAL X6S
J 0
(-7150 4075);
DISPLAY 0.617021 (-7150 4075);
PAINT SKYBLUE (-7150 4075);
FORCEPROP 1 LAST TOLERANCE 10%
J 0
(-7150 4125);
DISPLAY 0.617021 (-7150 4125);
PAINT SKYBLUE (-7150 4125);
FORCEPROP 1 LAST VOLTAGE 16V
J 0
(-7150 4175);
DISPLAY 0.617021 (-7150 4175);
PAINT SKYBLUE (-7150 4175);
FORCEPROP 1 LAST VALUE 10UF
J 0
(-7150 4225);
DISPLAY 0.617021 (-7150 4225);
PAINT SKYBLUE (-7150 4225);
FORCEPROP 1 LAST LOCATION C6N11
J 0
(-7150 4275);
DISPLAY 0.617021 (-7150 4275);
PAINT AQUA (-7150 4275);
FORCEPROP 1 LASTPIN (-7200 4275) $PN 1
J 0
(-7190 4255);
DISPLAY 0.617021 (-7190 4255);
PAINT ORANGE (-7190 4255);
FORCEPROP 1 LASTPIN (-7200 4075) $PN 2
J 0
(-7190 4055);
DISPLAY 0.617021 (-7190 4055);
PAINT ORANGE (-7190 4055);
FORCEPROP 2 LAST CDS_LIB mstr_discrete
J 0
(-7200 4175);
PAINT ORANGE (-7200 4175);
DISPLAY INVISIBLE (-7200 4175);
FORCEPROP 2 LAST ROOM PVCCIN_CPU0_PWR_VR
J 0
(-7150 4325);
DISPLAY 1.361702 (-7150 4325);
PAINT ORANGE (-7150 4325);
DISPLAY INVISIBLE (-7150 4325);
FORCEPROP 1 LAST PATH I42
J 0
(-7150 4325);
DISPLAY 0.978723 (-7150 4325);
PAINT WHITE (-7150 4325);
DISPLAY INVISIBLE (-7150 4325);
FORCEPROP 2 LAST SEC 1
J 0
(-7150 4375);
DISPLAY 0.680851 (-7150 4375);
PAINT MONO (-7150 4375);
DISPLAY INVISIBLE (-7150 4375);
FORCEPROP 2 LAST SEC_TYPE 0805
J 0
(-7150 4375);
DISPLAY 1.021277 (-7150 4375);
PAINT ORANGE (-7150 4375);
DISPLAY INVISIBLE (-7150 4375);
FORCEADD GND..1
(-7025 3725);
FORCEPROP 3 LASTPIN (-7025 3775) SIG_NAME GND\g
J 0
(-7015 3785);
DISPLAY 0.659574 (-7015 3785);
PAINT MONO (-7015 3785);
DISPLAY INVISIBLE (-7015 3785);
FORCEPROP 2 LAST ROOM PVCCIN_CPU0_PWR_VR
J 0
(-7575 3800);
DISPLAY 1.936170 (-7575 3800);
PAINT ORANGE (-7575 3800);
DISPLAY INVISIBLE (-7575 3800);
FORCEPROP 2 LAST BOM_COST PROC_VRD_VCCIN_CPU0
J 0
(-7400 3800);
DISPLAY 1.446809 (-7400 3800);
PAINT MONO (-7400 3800);
DISPLAY INVISIBLE (-7400 3800);
FORCEPROP 1 LAST BODY_TYPE PLUMBING
J 0
(-7070 3682);
DISPLAY 0.340426 (-7070 3682);
PAINT GREEN (-7070 3682);
DISPLAY INVISIBLE (-7070 3682);
FORCEPROP 1 LAST SIZE 1B
J 0
(-6950 3675);
DISPLAY 1.723404 (-6950 3675);
PAINT GREEN (-6950 3675);
DISPLAY INVISIBLE (-6950 3675);
FORCEPROP 1 LAST PATH I43
J 0
(-6950 3725);
DISPLAY 0.872340 (-6950 3725);
PAINT AQUA (-6950 3725);
DISPLAY INVISIBLE (-6950 3725);
FORCEPROP 2 LAST CDS_LIB mstr_symbols
J 0
(-7025 3725);
DISPLAY 1.936170 (-7025 3725);
PAINT ORANGE (-7025 3725);
DISPLAY INVISIBLE (-7025 3725);
FORCEPROP 1 LAST VOLTAGE 0
J 0
(-7025 3725);
PAINT SKYBLUE (-7025 3725);
DISPLAY INVISIBLE (-7025 3725);
FORCEPROP 1 LAST HDL_POWER GND
J 0
(-7025 3875);
DISPLAY 1.723404 (-7025 3875);
PAINT GREEN (-7025 3875);
DISPLAY INVISIBLE (-7025 3875);
FORCEADD VCC_CORE..1
(-575 2450);
FORCEPROP 3 LASTPIN (-575 2400) SIG_NAME VR_FET_SW_P12V_STBY_PVCCIN_CPU0\g
J 0
(-565 2410);
DISPLAY 0.659574 (-565 2410);
PAINT MONO (-565 2410);
DISPLAY INVISIBLE (-565 2410);
FORCEPROP 1 LAST HDL_POWER VR_FET_SW_P12V_STBY_PVCCIN_CPU0
J 1
(-575 2500);
DISPLAY 0.617021 (-575 2500);
PAINT GREEN (-575 2500);
FORCEPROP 2 LAST CDS_LIB mstr_symbols
J 0
(-575 2450);
PAINT ORANGE (-575 2450);
DISPLAY INVISIBLE (-575 2450);
FORCEPROP 1 LAST PATH I44
J 0
(-525 2475);
DISPLAY 0.872340 (-525 2475);
PAINT AQUA (-525 2475);
DISPLAY INVISIBLE (-525 2475);
FORCEADD CAPP..1
(-925 1975);
FORCEPROP 1 LAST VALUE 270UF
J 0
(-875 2025);
DISPLAY 0.617021 (-875 2025);
PAINT SKYBLUE (-875 2025);
FORCEPROP 1 LAST PACK_TYPE 2626
J 0
(-875 1825);
DISPLAY 0.617021 (-875 1825);
PAINT SKYBLUE (-875 1825);
FORCEPROP 1 LAST PART_NUMBER A31228-047
J 0
(-875 1775);
DISPLAY 0.617021 (-875 1775);
PAINT BLUE (-875 1775);
FORCEPROP 1 LAST LOCATION C4D2
J 0
(-875 2075);
DISPLAY 0.617021 (-875 2075);
PAINT AQUA (-875 2075);
FORCEPROP 1 LAST VOLTAGE 16V
J 0
(-875 1925);
DISPLAY 0.617021 (-875 1925);
PAINT SKYBLUE (-875 1925);
FORCEPROP 1 LASTPIN (-925 2075) $PN 1
J 0
(-915 2060);
DISPLAY 0.617021 (-915 2060);
PAINT ORANGE (-915 2060);
FORCEPROP 1 LAST TOLERANCE 20%
J 0
(-875 1975);
DISPLAY 0.617021 (-875 1975);
PAINT SKYBLUE (-875 1975);
FORCEPROP 1 LASTPIN (-925 1875) $PN 2
J 0
(-915 1860);
DISPLAY 0.617021 (-915 1860);
PAINT ORANGE (-915 1860);
FORCEPROP 1 LAST MATERIAL OSCON
J 0
(-875 1875);
DISPLAY 0.617021 (-875 1875);
PAINT SKYBLUE (-875 1875);
FORCEPROP 2 LAST SEC_TYPE 2626
J 0
(-875 2175);
DISPLAY 1.021277 (-875 2175);
PAINT ORANGE (-875 2175);
DISPLAY INVISIBLE (-875 2175);
FORCEPROP 2 LAST SEC 1
J 0
(-875 2175);
DISPLAY 0.680851 (-875 2175);
PAINT MONO (-875 2175);
DISPLAY INVISIBLE (-875 2175);
FORCEPROP 2 LAST CDS_LOCATION C4D2
J 0
(-875 2075);
DISPLAY 0.617021 (-875 2075);
PAINT AQUA (-875 2075);
DISPLAY INVISIBLE (-875 2075);
FORCEPROP 1 LAST PATH I48
J 0
(-875 2125);
DISPLAY 0.978723 (-875 2125);
PAINT ORANGE (-875 2125);
DISPLAY INVISIBLE (-875 2125);
FORCEPROP 2 LAST ROOM PVCCIN_CPU0_FILTER_VR
J 0
(-875 2125);
DISPLAY 1.361702 (-875 2125);
PAINT ORANGE (-875 2125);
DISPLAY INVISIBLE (-875 2125);
FORCEPROP 2 LAST CDS_LIB mstr_discrete
J 0
(-925 1975);
PAINT ORANGE (-925 1975);
DISPLAY INVISIBLE (-925 1975);
FORCEADD GND..1
(-1175 1575);
FORCEPROP 3 LASTPIN (-1175 1625) SIG_NAME GND\g
J 0
(-1165 1635);
DISPLAY 0.659574 (-1165 1635);
PAINT MONO (-1165 1635);
DISPLAY INVISIBLE (-1165 1635);
FORCEPROP 1 LAST PATH I49
J 0
(-1100 1575);
DISPLAY 0.872340 (-1100 1575);
PAINT AQUA (-1100 1575);
DISPLAY INVISIBLE (-1100 1575);
FORCEPROP 1 LAST HDL_POWER GND
J 0
(-1175 1725);
DISPLAY 0.893617 (-1175 1725);
PAINT GREEN (-1175 1725);
DISPLAY INVISIBLE (-1175 1725);
FORCEPROP 2 LAST CDS_LIB mstr_symbols
J 0
(-1175 1575);
PAINT ORANGE (-1175 1575);
DISPLAY INVISIBLE (-1175 1575);
FORCEPROP 1 LAST VOLTAGE 0
J 0
(-1175 1575);
PAINT SKYBLUE (-1175 1575);
DISPLAY INVISIBLE (-1175 1575);
FORCEPROP 1 LAST SIZE 1B
J 0
(-1100 1525);
DISPLAY 0.893617 (-1100 1525);
PAINT GREEN (-1100 1525);
DISPLAY INVISIBLE (-1100 1525);
FORCEPROP 1 LAST BODY_TYPE PLUMBING
J 0
(-1220 1532);
DISPLAY 0.340426 (-1220 1532);
PAINT GREEN (-1220 1532);
DISPLAY INVISIBLE (-1220 1532);
FORCEPROP 2 LAST BOM_COST PROC_VRD_VCCIN_CPU0
J 0
(-1550 1650);
PAINT MONO (-1550 1650);
DISPLAY INVISIBLE (-1550 1650);
FORCEPROP 2 LAST ROOM PVCCIN_CPU0_FILTER_VR
J 0
(-1725 1650);
PAINT ORANGE (-1725 1650);
DISPLAY INVISIBLE (-1725 1650);
FORCEADD CAPP..1
(-1400 2000);
FORCEPROP 1 LAST LOCATION C4E16
J 0
(-1350 2100);
DISPLAY 0.617021 (-1350 2100);
PAINT AQUA (-1350 2100);
FORCEPROP 1 LAST VALUE 270UF
J 0
(-1350 2050);
DISPLAY 0.617021 (-1350 2050);
PAINT SKYBLUE (-1350 2050);
FORCEPROP 1 LAST TOLERANCE 20%
J 0
(-1350 2000);
DISPLAY 0.617021 (-1350 2000);
PAINT SKYBLUE (-1350 2000);
FORCEPROP 1 LAST VOLTAGE 16V
J 0
(-1350 1950);
DISPLAY 0.617021 (-1350 1950);
PAINT SKYBLUE (-1350 1950);
FORCEPROP 1 LAST PART_NUMBER A31228-047
J 0
(-1350 1800);
DISPLAY 0.617021 (-1350 1800);
PAINT BLUE (-1350 1800);
FORCEPROP 1 LAST PACK_TYPE 2626
J 0
(-1350 1850);
DISPLAY 0.617021 (-1350 1850);
PAINT SKYBLUE (-1350 1850);
FORCEPROP 1 LAST MATERIAL OSCON
J 0
(-1350 1900);
DISPLAY 0.617021 (-1350 1900);
PAINT SKYBLUE (-1350 1900);
FORCEPROP 1 LASTPIN (-1400 1900) $PN 2
J 0
(-1390 1885);
DISPLAY 0.617021 (-1390 1885);
PAINT ORANGE (-1390 1885);
FORCEPROP 1 LASTPIN (-1400 2100) $PN 1
J 0
(-1390 2085);
DISPLAY 0.617021 (-1390 2085);
PAINT ORANGE (-1390 2085);
FORCEPROP 2 LAST ROOM PVCCIN_CPU0_FILTER_VR
J 0
(-1350 2150);
DISPLAY 1.361702 (-1350 2150);
PAINT ORANGE (-1350 2150);
DISPLAY INVISIBLE (-1350 2150);
FORCEPROP 1 LAST PATH I50
J 0
(-1350 2150);
DISPLAY 0.978723 (-1350 2150);
PAINT ORANGE (-1350 2150);
DISPLAY INVISIBLE (-1350 2150);
FORCEPROP 2 LAST CDS_LOCATION C4E16
J 0
(-1350 2100);
DISPLAY 0.617021 (-1350 2100);
PAINT AQUA (-1350 2100);
DISPLAY INVISIBLE (-1350 2100);
FORCEPROP 2 LAST SEC 1
J 0
(-1350 2200);
DISPLAY 0.680851 (-1350 2200);
PAINT MONO (-1350 2200);
DISPLAY INVISIBLE (-1350 2200);
FORCEPROP 2 LAST SEC_TYPE 2626
J 0
(-1350 2200);
DISPLAY 1.021277 (-1350 2200);
PAINT ORANGE (-1350 2200);
DISPLAY INVISIBLE (-1350 2200);
FORCEPROP 2 LAST CDS_LIB mstr_discrete
J 0
(-1400 2000);
PAINT ORANGE (-1400 2000);
DISPLAY INVISIBLE (-1400 2000);
FORCEADD OFFPAGE..2
(-4275 1825);
FORCEPROP 2 LAST $XR0 37 
J 0
(-4086 1825);
DISPLAY 0.638298 (-4086 1825);
PAINT MONO (-4086 1825);
FORCEPROP 2 LAST BOM_COST PROC_VRD_VCCIN_CPU0
J 0
(-3950 1875);
PAINT MONO (-3950 1875);
DISPLAY INVISIBLE (-3950 1875);
FORCEPROP 1 LAST OFFPAGE TRUE
J 0
(-3950 1700);
DISPLAY 0.893617 (-3950 1700);
PAINT GREEN (-3950 1700);
DISPLAY INVISIBLE (-3950 1700);
FORCEPROP 2 LAST PATH I56
J 0
(-3960 1885);
DISPLAY 1.021277 (-3960 1885);
PAINT ORANGE (-3960 1885);
DISPLAY INVISIBLE (-3960 1885);
FORCEPROP 2 LAST CDS_LIB mstr_standard
J 2
(-4275 1825);
PAINT ORANGE (-4275 1825);
DISPLAY INVISIBLE (-4275 1825);
FORCEPROP 1 LAST COMMENT_BODY TRUE
J 0
(-4320 1730);
DISPLAY 0.893617 (-4320 1730);
PAINT GREEN (-4320 1730);
DISPLAY INVISIBLE (-4320 1730);
FORCEPROP 2 LAST ROOM PVCCIN_CPU0_VSENSE_VR
J 0
(-4675 1900);
PAINT ORANGE (-4675 1900);
DISPLAY INVISIBLE (-4675 1900);
FORCEADD OFFPAGE..2
(-4275 1375);
FORCEPROP 2 LAST $XR0 37 
J 0
(-4086 1375);
DISPLAY 0.638298 (-4086 1375);
PAINT MONO (-4086 1375);
FORCEPROP 2 LAST BOM_COST PROC_VRD_VCCIN_CPU0
J 0
(-4075 1425);
PAINT MONO (-4075 1425);
DISPLAY INVISIBLE (-4075 1425);
FORCEPROP 1 LAST OFFPAGE TRUE
J 0
(-3950 1250);
DISPLAY 0.893617 (-3950 1250);
PAINT GREEN (-3950 1250);
DISPLAY INVISIBLE (-3950 1250);
FORCEPROP 2 LAST PATH I57
J 0
(-4085 1435);
DISPLAY 1.021277 (-4085 1435);
PAINT ORANGE (-4085 1435);
DISPLAY INVISIBLE (-4085 1435);
FORCEPROP 2 LAST CDS_LIB mstr_standard
J 0
(-4275 1375);
PAINT ORANGE (-4275 1375);
DISPLAY INVISIBLE (-4275 1375);
FORCEPROP 1 LAST COMMENT_BODY TRUE
J 0
(-4320 1280);
DISPLAY 0.893617 (-4320 1280);
PAINT GREEN (-4320 1280);
DISPLAY INVISIBLE (-4320 1280);
FORCEPROP 2 LAST ROOM PVCCIN_CPU0_VSENSE_VR
J 0
(-4675 1450);
PAINT ORANGE (-4675 1450);
DISPLAY INVISIBLE (-4675 1450);
FORCEADD PVCCIN_CPU0..1
(-4625 2375);
FORCEPROP 3 LASTPIN (-4625 2325) SIG_NAME PVCCIN_CPU0\g
J 0
(-4615 2335);
DISPLAY 0.659574 (-4615 2335);
PAINT MONO (-4615 2335);
DISPLAY INVISIBLE (-4615 2335);
FORCEPROP 1 LAST PATH I58
J 0
(-4575 2400);
DISPLAY 0.872340 (-4575 2400);
PAINT AQUA (-4575 2400);
DISPLAY INVISIBLE (-4575 2400);
FORCEPROP 1 LAST BODY_TYPE PLUMBING
J 0
(-4670 2332);
DISPLAY 0.340426 (-4670 2332);
PAINT GREEN (-4670 2332);
DISPLAY INVISIBLE (-4670 2332);
FORCEPROP 2 LAST CDS_LIB mstr_symbols
J 0
(-4625 2375);
PAINT ORANGE (-4625 2375);
DISPLAY INVISIBLE (-4625 2375);
FORCEPROP 1 LAST VOLTAGE 2.0V
J 0
(-4670 2332);
DISPLAY 0.340426 (-4670 2332);
PAINT SKYBLUE (-4670 2332);
DISPLAY INVISIBLE (-4670 2332);
FORCEPROP 1 LAST HDL_POWER PVCCIN_CPU0
J 1
(-4625 2425);
DISPLAY 0.872340 (-4625 2425);
PAINT GREEN (-4625 2425);
DISPLAY INVISIBLE (-4625 2425);
FORCEADD GND..1
(-4800 700);
FORCEPROP 3 LASTPIN (-4800 750) SIG_NAME GND\g
J 0
(-4790 760);
DISPLAY 0.659574 (-4790 760);
PAINT MONO (-4790 760);
DISPLAY INVISIBLE (-4790 760);
FORCEPROP 1 LAST HDL_POWER GND
J 0
(-4800 850);
DISPLAY 0.893617 (-4800 850);
PAINT GREEN (-4800 850);
DISPLAY INVISIBLE (-4800 850);
FORCEPROP 1 LAST VOLTAGE 0
J 0
(-4800 700);
PAINT SKYBLUE (-4800 700);
DISPLAY INVISIBLE (-4800 700);
FORCEPROP 1 LAST SIZE 1B
J 0
(-4725 650);
DISPLAY 0.893617 (-4725 650);
PAINT GREEN (-4725 650);
DISPLAY INVISIBLE (-4725 650);
FORCEPROP 2 LAST CDS_LIB mstr_symbols
J 0
(-4800 700);
PAINT ORANGE (-4800 700);
DISPLAY INVISIBLE (-4800 700);
FORCEPROP 1 LAST BODY_TYPE PLUMBING
J 0
(-4845 657);
DISPLAY 0.340426 (-4845 657);
PAINT GREEN (-4845 657);
DISPLAY INVISIBLE (-4845 657);
FORCEPROP 1 LAST PATH I59
J 0
(-4725 700);
DISPLAY 0.872340 (-4725 700);
PAINT AQUA (-4725 700);
DISPLAY INVISIBLE (-4725 700);
FORCEPROP 2 LAST BOM_COST PROC_VRD_VCCIN_CPU0
J 0
(-5175 775);
PAINT MONO (-5175 775);
DISPLAY INVISIBLE (-5175 775);
FORCEPROP 2 LAST ROOM PVCCIN_CPU0_VSENSE_VR
J 0
(-5350 775);
PAINT ORANGE (-5350 775);
DISPLAY INVISIBLE (-5350 775);
FORCEADD RES..1
(-5475 2225);
FORCEPROP 1 LAST MATERIAL CHIP
J 0
(-5450 2100);
DISPLAY 0.638298 (-5450 2100);
PAINT SKYBLUE (-5450 2100);
FORCEPROP 1 LAST WATTAGE 1/16W
J 2
(-5475 2100);
DISPLAY 0.617021 (-5475 2100);
PAINT SKYBLUE (-5475 2100);
FORCEPROP 1 LAST TOLERANCE 1%
J 0
(-5425 2150);
DISPLAY 0.617021 (-5425 2150);
PAINT SKYBLUE (-5425 2150);
FORCEPROP 1 LASTPIN (-5375 2225) $PN 2
J 0
(-5413 2237);
DISPLAY 0.617021 (-5413 2237);
PAINT GREEN (-5413 2237);
FORCEPROP 1 LAST LOCATION R4E14
J 0
(-5525 2275);
DISPLAY 0.617021 (-5525 2275);
PAINT AQUA (-5525 2275);
FORCEPROP 1 LAST PART_NUMBER G21796-017
J 0
(-5525 2325);
DISPLAY 0.617021 (-5525 2325);
PAINT BLUE (-5525 2325);
FORCEPROP 1 LASTPIN (-5575 2225) $PN 1
J 0
(-5563 2237);
DISPLAY 0.617021 (-5563 2237);
PAINT GREEN (-5563 2237);
FORCEPROP 1 LAST PACK_TYPE 0402
J 0
(-5550 2050);
DISPLAY 0.617021 (-5550 2050);
PAINT SKYBLUE (-5550 2050);
FORCEPROP 1 LAST VALUE 100.0
J 2
(-5475 2150);
DISPLAY 0.617021 (-5475 2150);
PAINT SKYBLUE (-5475 2150);
FORCEPROP 2 LAST CDS_SEC 1
J 0
(-5525 2425);
PAINT MONO (-5525 2425);
DISPLAY INVISIBLE (-5525 2425);
FORCEPROP 2 LAST $SEC 1
J 0
(-5525 2425);
PAINT MONO (-5525 2425);
DISPLAY INVISIBLE (-5525 2425);
FORCEPROP 1 LAST PATH I60
J 0
(-5525 2375);
DISPLAY 0.978723 (-5525 2375);
PAINT WHITE (-5525 2375);
DISPLAY INVISIBLE (-5525 2375);
FORCEPROP 2 LAST ROOM PVCCIN_CPU0_VSENSE_VR
J 0
(-5525 2325);
PAINT ORANGE (-5525 2325);
DISPLAY INVISIBLE (-5525 2325);
FORCEPROP 2 LAST BOM_COST PROC_VRD_VCCIN_CPU0
J 0
(-5525 2375);
PAINT MONO (-5525 2375);
DISPLAY INVISIBLE (-5525 2375);
FORCEPROP 2 LAST CDS_LIB mstr_discrete
J 0
(-5475 2225);
PAINT ORANGE (-5475 2225);
DISPLAY INVISIBLE (-5475 2225);
FORCEPROP 2 LAST CDS_LOCATION R4E14
J 0
(-5525 2275);
DISPLAY 0.617021 (-5525 2275);
PAINT AQUA (-5525 2275);
DISPLAY INVISIBLE (-5525 2275);
FORCEADD RES..1
(-5475 1825);
FORCEPROP 1 LAST VALUE 0.0
J 2
(-5500 1750);
DISPLAY 0.617021 (-5500 1750);
PAINT SKYBLUE (-5500 1750);
FORCEPROP 1 LAST TOLERANCE 5%
J 0
(-5475 1750);
DISPLAY 0.617021 (-5475 1750);
PAINT SKYBLUE (-5475 1750);
FORCEPROP 1 LAST PART_NUMBER G21497-005
J 0
(-5600 1925);
DISPLAY 0.617021 (-5600 1925);
PAINT BLUE (-5600 1925);
FORCEPROP 2 LAST NO_XNET_CONNECTION 1
J 0
(-5375 1975);
PAINT MONO (-5375 1975);
FORCEPROP 1 LAST LOCATION R4E16
J 0
(-5525 1875);
DISPLAY 0.617021 (-5525 1875);
PAINT AQUA (-5525 1875);
FORCEPROP 1 LASTPIN (-5375 1825) $PN 2
J 0
(-5413 1837);
DISPLAY 0.617021 (-5413 1837);
PAINT GREEN (-5413 1837);
FORCEPROP 1 LAST WATTAGE 1/16W
J 2
(-5500 1675);
DISPLAY 0.617021 (-5500 1675);
PAINT SKYBLUE (-5500 1675);
FORCEPROP 1 LAST PACK_TYPE 0402
J 0
(-5600 1625);
DISPLAY 0.617021 (-5600 1625);
PAINT SKYBLUE (-5600 1625);
FORCEPROP 1 LASTPIN (-5575 1825) $PN 1
J 0
(-5563 1837);
DISPLAY 0.617021 (-5563 1837);
PAINT GREEN (-5563 1837);
FORCEPROP 1 LAST MATERIAL CHIP
J 0
(-5475 1675);
DISPLAY 0.617021 (-5475 1675);
PAINT SKYBLUE (-5475 1675);
FORCEPROP 2 LAST CDS_SEC 1
J 0
(-5525 2025);
PAINT MONO (-5525 2025);
DISPLAY INVISIBLE (-5525 2025);
FORCEPROP 2 LAST $SEC 1
J 0
(-5525 2025);
PAINT MONO (-5525 2025);
DISPLAY INVISIBLE (-5525 2025);
FORCEPROP 2 LAST CDS_LIB mstr_discrete
J 0
(-5475 1825);
PAINT ORANGE (-5475 1825);
DISPLAY INVISIBLE (-5475 1825);
FORCEPROP 2 LAST BOM_COST PROC_VRD_VCCIN_CPU0
J 0
(-5600 1975);
PAINT MONO (-5600 1975);
DISPLAY INVISIBLE (-5600 1975);
FORCEPROP 2 LAST CDS_LOCATION R4E16
J 0
(-5525 1875);
DISPLAY 0.617021 (-5525 1875);
PAINT AQUA (-5525 1875);
DISPLAY INVISIBLE (-5525 1875);
FORCEPROP 1 LAST PATH I61
J 0
(-5525 1975);
DISPLAY 0.978723 (-5525 1975);
PAINT WHITE (-5525 1975);
DISPLAY INVISIBLE (-5525 1975);
FORCEPROP 2 LAST ROOM PVCCIN_CPU0_VSENSE_VR
J 0
(-5525 1925);
PAINT ORANGE (-5525 1925);
DISPLAY INVISIBLE (-5525 1925);
FORCEADD RES..1
(-5450 1375);
FORCEPROP 1 LAST TOLERANCE 5%
J 0
(-5450 1300);
DISPLAY 0.617021 (-5450 1300);
PAINT SKYBLUE (-5450 1300);
FORCEPROP 1 LAST LOCATION R4E17
J 0
(-5500 1425);
DISPLAY 0.617021 (-5500 1425);
PAINT AQUA (-5500 1425);
FORCEPROP 1 LAST PART_NUMBER G21497-005
J 0
(-5575 1475);
DISPLAY 0.617021 (-5575 1475);
PAINT BLUE (-5575 1475);
FORCEPROP 1 LAST WATTAGE 1/16W
J 2
(-5475 1225);
DISPLAY 0.617021 (-5475 1225);
PAINT SKYBLUE (-5475 1225);
FORCEPROP 1 LAST VALUE 0.0
J 2
(-5475 1300);
DISPLAY 0.617021 (-5475 1300);
PAINT SKYBLUE (-5475 1300);
FORCEPROP 1 LAST PACK_TYPE 0402
J 0
(-5575 1175);
DISPLAY 0.617021 (-5575 1175);
PAINT SKYBLUE (-5575 1175);
FORCEPROP 1 LASTPIN (-5550 1375) $PN 1
J 0
(-5538 1387);
DISPLAY 0.617021 (-5538 1387);
PAINT GREEN (-5538 1387);
FORCEPROP 1 LAST MATERIAL CHIP
J 0
(-5450 1225);
DISPLAY 0.617021 (-5450 1225);
PAINT SKYBLUE (-5450 1225);
FORCEPROP 1 LASTPIN (-5350 1375) $PN 2
J 0
(-5388 1387);
DISPLAY 0.617021 (-5388 1387);
PAINT GREEN (-5388 1387);
FORCEPROP 2 LAST NO_XNET_CONNECTION 1
J 0
(-5500 1575);
PAINT MONO (-5500 1575);
FORCEPROP 2 LAST CDS_SEC 1
J 0
(-5500 1575);
PAINT MONO (-5500 1575);
DISPLAY INVISIBLE (-5500 1575);
FORCEPROP 2 LAST $SEC 1
J 0
(-5500 1575);
PAINT MONO (-5500 1575);
DISPLAY INVISIBLE (-5500 1575);
FORCEPROP 2 LAST BOM_COST PROC_VRD_VCCIN_CPU0
J 0
(-5575 1525);
PAINT MONO (-5575 1525);
DISPLAY INVISIBLE (-5575 1525);
FORCEPROP 1 LAST PATH I62
J 0
(-5500 1525);
DISPLAY 0.978723 (-5500 1525);
PAINT WHITE (-5500 1525);
DISPLAY INVISIBLE (-5500 1525);
FORCEPROP 2 LAST ROOM PVCCIN_CPU0_VSENSE_VR
J 0
(-5500 1475);
PAINT ORANGE (-5500 1475);
DISPLAY INVISIBLE (-5500 1475);
FORCEPROP 2 LAST CDS_LOCATION R4E17
J 0
(-5500 1425);
DISPLAY 0.617021 (-5500 1425);
PAINT AQUA (-5500 1425);
DISPLAY INVISIBLE (-5500 1425);
FORCEPROP 2 LAST CDS_LIB mstr_discrete
J 0
(-5450 1375);
PAINT ORANGE (-5450 1375);
DISPLAY INVISIBLE (-5450 1375);
FORCEADD RES..2
(-6275 1625);
FORCEPROP 1 LAST WATTAGE 1/16W
J 0
(-6235 1600);
DISPLAY 0.617021 (-6235 1600);
PAINT SKYBLUE (-6235 1600);
FORCEPROP 1 LAST MATERIAL EMPTY
J 0
(-6235 1550);
DISPLAY 0.617021 (-6235 1550);
PAINT RED (-6235 1550);
FORCEPROP 1 LAST TOLERANCE 1%
J 0
(-6230 1650);
DISPLAY 0.617021 (-6230 1650);
PAINT SKYBLUE (-6230 1650);
FORCEPROP 1 LAST VALUE 1.00K
J 0
(-6230 1700);
DISPLAY 0.617021 (-6230 1700);
PAINT SKYBLUE (-6230 1700);
FORCEPROP 1 LAST LOCATION R4E15
J 0
(-6230 1750);
DISPLAY 0.617021 (-6230 1750);
PAINT AQUA (-6230 1750);
FORCEPROP 2 LAST NO_XNET_CONNECTION 1
J 0
(-6225 1850);
PAINT MONO (-6225 1850);
FORCEPROP 1 LAST PACK_TYPE 0402
J 0
(-6235 1450);
DISPLAY 0.617021 (-6235 1450);
PAINT SKYBLUE (-6235 1450);
FORCEPROP 1 LASTPIN (-6275 1725) $PN 1
J 0
(-6270 1687);
DISPLAY 0.617021 (-6270 1687);
PAINT GREEN (-6270 1687);
FORCEPROP 1 LASTPIN (-6275 1525) $PN 2
J 0
(-6270 1535);
DISPLAY 0.617021 (-6270 1535);
PAINT GREEN (-6270 1535);
FORCEPROP 1 LAST PART_NUMBER G21796-026
J 0
(-6235 1500);
DISPLAY 0.617021 (-6235 1500);
PAINT BLUE (-6235 1500);
FORCEPROP 2 LAST BOM_COST PROC_VRD_VCCIN_CPU0
J 0
(-6225 1800);
PAINT MONO (-6225 1800);
DISPLAY INVISIBLE (-6225 1800);
FORCEPROP 2 LAST CDS_SEC 1
J 0
(-6225 1850);
PAINT MONO (-6225 1850);
DISPLAY INVISIBLE (-6225 1850);
FORCEPROP 2 LAST $SEC 1
J 0
(-6225 1850);
PAINT MONO (-6225 1850);
DISPLAY INVISIBLE (-6225 1850);
FORCEPROP 1 LAST PATH I63
J 0
(-6225 1800);
DISPLAY 0.978723 (-6225 1800);
PAINT WHITE (-6225 1800);
DISPLAY INVISIBLE (-6225 1800);
FORCEPROP 2 LAST ROOM PVCCIN_CPU0_VSENSE_VR
J 0
(-6225 1800);
PAINT MONO (-6225 1800);
DISPLAY INVISIBLE (-6225 1800);
FORCEPROP 2 LAST CDS_LOCATION R4E15
J 0
(-6230 1750);
DISPLAY 0.617021 (-6230 1750);
PAINT AQUA (-6230 1750);
DISPLAY INVISIBLE (-6230 1750);
FORCEPROP 2 LAST CDS_LIB mstr_discrete
J 0
(-6275 1625);
PAINT ORANGE (-6275 1625);
DISPLAY INVISIBLE (-6275 1625);
FORCEADD RES..1
(-5450 975);
FORCEPROP 1 LAST MATERIAL CHIP
J 0
(-5425 850);
DISPLAY 0.638298 (-5425 850);
PAINT SKYBLUE (-5425 850);
FORCEPROP 1 LAST PACK_TYPE 0402
J 0
(-5525 800);
DISPLAY 0.617021 (-5525 800);
PAINT SKYBLUE (-5525 800);
FORCEPROP 1 LAST TOLERANCE 1%
J 0
(-5400 900);
DISPLAY 0.617021 (-5400 900);
PAINT SKYBLUE (-5400 900);
FORCEPROP 1 LAST PART_NUMBER G21796-017
J 0
(-5500 1075);
DISPLAY 0.617021 (-5500 1075);
PAINT BLUE (-5500 1075);
FORCEPROP 1 LASTPIN (-5550 975) $PN 1
J 0
(-5538 987);
DISPLAY 0.617021 (-5538 987);
PAINT GREEN (-5538 987);
FORCEPROP 1 LAST WATTAGE 1/16W
J 2
(-5450 850);
DISPLAY 0.617021 (-5450 850);
PAINT SKYBLUE (-5450 850);
FORCEPROP 1 LAST VALUE 100.0
J 2
(-5450 900);
DISPLAY 0.617021 (-5450 900);
PAINT SKYBLUE (-5450 900);
FORCEPROP 1 LASTPIN (-5350 975) $PN 2
J 0
(-5388 987);
DISPLAY 0.617021 (-5388 987);
PAINT GREEN (-5388 987);
FORCEPROP 1 LAST LOCATION R4E18
J 0
(-5500 1025);
DISPLAY 0.617021 (-5500 1025);
PAINT AQUA (-5500 1025);
FORCEPROP 2 LAST CDS_SEC 1
J 0
(-5500 1175);
PAINT MONO (-5500 1175);
DISPLAY INVISIBLE (-5500 1175);
FORCEPROP 2 LAST $SEC 1
J 0
(-5500 1175);
PAINT MONO (-5500 1175);
DISPLAY INVISIBLE (-5500 1175);
FORCEPROP 2 LAST CDS_LOCATION R4E18
J 0
(-5500 1025);
DISPLAY 0.617021 (-5500 1025);
PAINT AQUA (-5500 1025);
DISPLAY INVISIBLE (-5500 1025);
FORCEPROP 1 LAST PATH I64
J 0
(-5500 1125);
DISPLAY 0.978723 (-5500 1125);
PAINT WHITE (-5500 1125);
DISPLAY INVISIBLE (-5500 1125);
FORCEPROP 2 LAST ROOM PVCCIN_CPU0_VSENSE_VR
J 0
(-5500 1075);
PAINT ORANGE (-5500 1075);
DISPLAY INVISIBLE (-5500 1075);
FORCEPROP 2 LAST BOM_COST PROC_VRD_VCCIN_CPU0
J 0
(-5500 1125);
PAINT MONO (-5500 1125);
DISPLAY INVISIBLE (-5500 1125);
FORCEPROP 2 LAST CDS_LIB mstr_discrete
J 0
(-5450 975);
PAINT ORANGE (-5450 975);
DISPLAY INVISIBLE (-5450 975);
FORCEADD OFFPAGE..1
(-7600 1775);
FORCEPROP 2 LAST $XR0 201 
J 0
(-7852 1775);
DISPLAY 0.638298 (-7852 1775);
PAINT MONO (-7852 1775);
FORCEPROP 2 LAST CDS_LIB mstr_standard
J 2
(-7600 1775);
PAINT ORANGE (-7600 1775);
DISPLAY INVISIBLE (-7600 1775);
FORCEPROP 1 LAST OFFPAGE TRUE
J 0
(-7275 1650);
DISPLAY 0.893617 (-7275 1650);
PAINT GREEN (-7275 1650);
DISPLAY INVISIBLE (-7275 1650);
FORCEPROP 1 LAST COMMENT_BODY TRUE
J 0
(-7475 1675);
DISPLAY 0.893617 (-7475 1675);
PAINT GREEN (-7475 1675);
DISPLAY INVISIBLE (-7475 1675);
FORCEPROP 2 LAST PATH I65
J 0
(-7810 1835);
DISPLAY 1.021277 (-7810 1835);
PAINT ORANGE (-7810 1835);
DISPLAY INVISIBLE (-7810 1835);
FORCEPROP 2 LAST BOM_COST PROC_VRD_VCCIN_CPU0
J 0
(-7800 1825);
PAINT MONO (-7800 1825);
DISPLAY INVISIBLE (-7800 1825);
FORCEPROP 2 LAST ROOM PVCCIN_CPU0_VSENSE_VR
J 0
(-8125 1850);
PAINT ORANGE (-8125 1850);
DISPLAY INVISIBLE (-8125 1850);
FORCEADD OFFPAGE..1
(-7600 1500);
FORCEPROP 2 LAST $XR0 201 
J 0
(-7852 1500);
DISPLAY 0.638298 (-7852 1500);
PAINT MONO (-7852 1500);
FORCEPROP 2 LAST CDS_LIB mstr_standard
J 0
(-7600 1500);
PAINT ORANGE (-7600 1500);
DISPLAY INVISIBLE (-7600 1500);
FORCEPROP 1 LAST OFFPAGE TRUE
J 0
(-7275 1375);
DISPLAY 0.893617 (-7275 1375);
PAINT GREEN (-7275 1375);
DISPLAY INVISIBLE (-7275 1375);
FORCEPROP 1 LAST COMMENT_BODY TRUE
J 0
(-7475 1400);
DISPLAY 0.893617 (-7475 1400);
PAINT GREEN (-7475 1400);
DISPLAY INVISIBLE (-7475 1400);
FORCEPROP 2 LAST PATH I66
J 0
(-7810 1560);
DISPLAY 1.021277 (-7810 1560);
PAINT ORANGE (-7810 1560);
DISPLAY INVISIBLE (-7810 1560);
FORCEPROP 2 LAST BOM_COST PROC_VRD_VCCIN_CPU0
J 0
(-7800 1550);
PAINT MONO (-7800 1550);
DISPLAY INVISIBLE (-7800 1550);
FORCEPROP 2 LAST ROOM PVCCIN_CPU0_VSENSE_VR
J 0
(-8125 1575);
PAINT ORANGE (-8125 1575);
DISPLAY INVISIBLE (-8125 1575);
FORCEADD CAPP..1
(-575 1975);
FORCEPROP 1 LAST LOCATION C4C12
J 0
(-525 2075);
DISPLAY 0.617021 (-525 2075);
PAINT AQUA (-525 2075);
FORCEPROP 1 LAST TOLERANCE 20%
J 0
(-525 1975);
DISPLAY 0.617021 (-525 1975);
PAINT SKYBLUE (-525 1975);
FORCEPROP 1 LAST VOLTAGE 16V
J 0
(-525 1925);
DISPLAY 0.617021 (-525 1925);
PAINT SKYBLUE (-525 1925);
FORCEPROP 1 LAST MATERIAL OSCON
J 0
(-525 1875);
DISPLAY 0.617021 (-525 1875);
PAINT SKYBLUE (-525 1875);
FORCEPROP 1 LAST VALUE 270UF
J 0
(-525 2025);
DISPLAY 0.617021 (-525 2025);
PAINT SKYBLUE (-525 2025);
FORCEPROP 1 LAST PART_NUMBER A31228-047
J 0
(-525 1775);
DISPLAY 0.617021 (-525 1775);
PAINT BLUE (-525 1775);
FORCEPROP 1 LAST PACK_TYPE 2626
J 0
(-525 1825);
DISPLAY 0.617021 (-525 1825);
PAINT SKYBLUE (-525 1825);
FORCEPROP 1 LASTPIN (-575 1875) $PN 2
J 0
(-565 1860);
DISPLAY 0.617021 (-565 1860);
PAINT ORANGE (-565 1860);
FORCEPROP 1 LASTPIN (-575 2075) $PN 1
J 0
(-565 2060);
DISPLAY 0.617021 (-565 2060);
PAINT ORANGE (-565 2060);
FORCEPROP 2 LAST SEC_TYPE 2626
J 0
(-525 2175);
DISPLAY 1.021277 (-525 2175);
PAINT ORANGE (-525 2175);
DISPLAY INVISIBLE (-525 2175);
FORCEPROP 2 LAST SEC 1
J 0
(-525 2175);
DISPLAY 0.680851 (-525 2175);
PAINT MONO (-525 2175);
DISPLAY INVISIBLE (-525 2175);
FORCEPROP 2 LAST ROOM PVCCIN_CPU0_FILTER_VR
J 0
(-525 2125);
DISPLAY 1.361702 (-525 2125);
PAINT ORANGE (-525 2125);
DISPLAY INVISIBLE (-525 2125);
FORCEPROP 2 LAST CDS_LOCATION C4C12
J 0
(-525 2075);
DISPLAY 0.617021 (-525 2075);
PAINT AQUA (-525 2075);
DISPLAY INVISIBLE (-525 2075);
FORCEPROP 1 LAST PATH I67
J 0
(-525 2125);
DISPLAY 0.978723 (-525 2125);
PAINT ORANGE (-525 2125);
DISPLAY INVISIBLE (-525 2125);
FORCEPROP 2 LAST CDS_LIB mstr_discrete
J 0
(-575 1975);
PAINT ORANGE (-575 1975);
DISPLAY INVISIBLE (-575 1975);
FORCEADD P12V_STBY..1
(-3325 2425);
FORCEPROP 3 LASTPIN (-3325 2375) SIG_NAME P12V_STBY\g
J 0
(-3315 2385);
DISPLAY 0.659574 (-3315 2385);
PAINT MONO (-3315 2385);
DISPLAY INVISIBLE (-3315 2385);
FORCEPROP 2 LAST CDS_LIB mstr_symbols
J 0
(-3325 2425);
PAINT ORANGE (-3325 2425);
DISPLAY INVISIBLE (-3325 2425);
FORCEPROP 1 LAST SIZE 1B
J 0
(-3280 2447);
DISPLAY 0.340426 (-3280 2447);
PAINT GREEN (-3280 2447);
DISPLAY INVISIBLE (-3280 2447);
FORCEPROP 1 LAST PATH I68
J 0
(-3280 2427);
DISPLAY 0.340426 (-3280 2427);
PAINT GREEN (-3280 2427);
DISPLAY INVISIBLE (-3280 2427);
FORCEPROP 1 LAST BODY_TYPE PLUMBING
J 0
(-3370 2382);
DISPLAY 0.340426 (-3370 2382);
PAINT GREEN (-3370 2382);
DISPLAY INVISIBLE (-3370 2382);
FORCEPROP 1 LAST VOLTAGE 12.0V
J 0
(-3370 2382);
DISPLAY 0.340426 (-3370 2382);
PAINT SKYBLUE (-3370 2382);
DISPLAY INVISIBLE (-3370 2382);
FORCEPROP 1 LAST HDL_POWER P12V_STBY
J 0
(-3625 2300);
DISPLAY 0.872340 (-3625 2300);
PAINT ORANGE (-3625 2300);
DISPLAY INVISIBLE (-3625 2300);
FORCEADD P5V_STBY..1
(-4675 4875);
FORCEPROP 3 LASTPIN (-4675 4825) SIG_NAME P5V_STBY\g
J 0
(-4665 4835);
DISPLAY 0.659574 (-4665 4835);
PAINT MONO (-4665 4835);
DISPLAY INVISIBLE (-4665 4835);
FORCEPROP 1 LAST PATH I69
J 0
(-4630 4877);
DISPLAY 0.340426 (-4630 4877);
PAINT GREEN (-4630 4877);
DISPLAY INVISIBLE (-4630 4877);
FORCEPROP 2 LAST CDS_LIB mstr_symbols
J 0
(-4675 4875);
PAINT ORANGE (-4675 4875);
DISPLAY INVISIBLE (-4675 4875);
FORCEPROP 1 LAST SIZE 1B
J 0
(-4630 4897);
DISPLAY 0.340426 (-4630 4897);
PAINT GREEN (-4630 4897);
DISPLAY INVISIBLE (-4630 4897);
FORCEPROP 1 LAST BODY_TYPE PLUMBING
J 0
(-4720 4832);
DISPLAY 0.340426 (-4720 4832);
PAINT GREEN (-4720 4832);
DISPLAY INVISIBLE (-4720 4832);
FORCEPROP 1 LAST VOLTAGE 5.0V
J 0
(-4720 4832);
DISPLAY 0.340426 (-4720 4832);
PAINT SKYBLUE (-4720 4832);
DISPLAY INVISIBLE (-4720 4832);
FORCEPROP 1 LAST HDL_POWER P5V_STBY
J 0
(-4975 4750);
DISPLAY 0.872340 (-4975 4750);
PAINT ORANGE (-4975 4750);
DISPLAY INVISIBLE (-4975 4750);
FORCEADD CAP_A..1
(-400 3425);
FORCEPROP 0 LAST GROUP PWR_MLCC_CAP
J 0
(-344 3162);
DISPLAY 0.638298 (-344 3162);
PAINT BROWN (-344 3162);
DISPLAY BOTH (-344 3162);
FORCEPROP 1 LAST LOCATION C6R2
J 0
(-350 3575);
DISPLAY 0.617021 (-350 3575);
PAINT AQUA (-350 3575);
FORCEPROP 1 LASTPIN (-400 3525) $PN 1
J 0
(-390 3505);
DISPLAY 0.617021 (-390 3505);
PAINT ORANGE (-390 3505);
FORCEPROP 1 LAST PART_NUMBER E15431-004
J 0
(-350 3325);
DISPLAY 0.617021 (-350 3325);
PAINT BLUE (-350 3325);
FORCEPROP 1 LAST PACK_TYPE 0603V
J 0
(-350 3275);
DISPLAY 0.617021 (-350 3275);
PAINT SKYBLUE (-350 3275);
FORCEPROP 1 LAST MATERIAL X6S
J 0
(-350 3375);
DISPLAY 0.617021 (-350 3375);
PAINT SKYBLUE (-350 3375);
FORCEPROP 1 LAST TOLERANCE 20%
J 0
(-350 3425);
DISPLAY 0.617021 (-350 3425);
PAINT SKYBLUE (-350 3425);
FORCEPROP 1 LAST VOLTAGE 4V
J 0
(-350 3475);
DISPLAY 0.617021 (-350 3475);
PAINT SKYBLUE (-350 3475);
FORCEPROP 1 LAST VALUE 22.0UF
J 0
(-350 3525);
DISPLAY 0.617021 (-350 3525);
PAINT SKYBLUE (-350 3525);
FORCEPROP 1 LASTPIN (-400 3325) $PN 2
J 0
(-390 3305);
DISPLAY 0.617021 (-390 3305);
PAINT ORANGE (-390 3305);
FORCEPROP 1 LAST PATH I70
J 0
(-350 3575);
DISPLAY 0.978723 (-350 3575);
PAINT WHITE (-350 3575);
DISPLAY INVISIBLE (-350 3575);
FORCEPROP 2 LAST SEC 1
J 0
(-350 3625);
DISPLAY 0.680851 (-350 3625);
PAINT MONO (-350 3625);
DISPLAY INVISIBLE (-350 3625);
FORCEPROP 2 LAST SEC_TYPE 0603V
J 0
(-350 3625);
DISPLAY 1.021277 (-350 3625);
PAINT ORANGE (-350 3625);
DISPLAY INVISIBLE (-350 3625);
FORCEPROP 2 LAST CDS_SEC 1
J 0
(-350 3575);
PAINT ORANGE (-350 3575);
DISPLAY INVISIBLE (-350 3575);
FORCEPROP 2 LAST CDS_LOCATION C6R2
J 0
(-350 3525);
DISPLAY 0.617021 (-350 3525);
PAINT AQUA (-350 3525);
DISPLAY INVISIBLE (-350 3525);
FORCEPROP 2 LAST CDS_LIB dev_discrete
J 0
(-400 3425);
PAINT ORANGE (-400 3425);
DISPLAY INVISIBLE (-400 3425);
FORCEADD IR354XX..1
(-3125 3925);
FORCEPROP 1 LAST LOCATION EU4C2
J 0
(-3575 4725);
DISPLAY 0.617021 (-3575 4725);
PAINT AQUA (-3575 4725);
FORCEPROP 2 LASTPIN (-2625 4475) $PN 38
J 0
(-2615 4485);
DISPLAY 0.617021 (-2615 4485);
PAINT MONO (-2615 4485);
FORCEPROP 2 LASTPIN (-2625 4225) $PN 31
J 0
(-2615 4235);
DISPLAY 0.617021 (-2615 4235);
PAINT MONO (-2615 4235);
FORCEPROP 2 LASTPIN (-2625 3525) $PN 2
J 0
(-2615 3535);
DISPLAY 0.617021 (-2615 3535);
PAINT MONO (-2615 3535);
FORCEPROP 2 LASTPIN (-3625 4075) $PN 1
J 2
(-3635 4085);
DISPLAY 0.617021 (-3635 4085);
PAINT MONO (-3635 4085);
FORCEPROP 2 LASTPIN (-3625 3825) $PN 34
J 2
(-3635 3835);
DISPLAY 0.617021 (-3635 3835);
PAINT MONO (-3635 3835);
FORCEPROP 2 LASTPIN (-3625 3925) $PN 6
J 2
(-3635 3935);
DISPLAY 0.617021 (-3635 3935);
PAINT MONO (-3635 3935);
FORCEPROP 1 LAST PART_NUMBER H73688-001
J 0
(-3500 3225);
DISPLAY 0.617021 (-3500 3225);
PAINT BLUE (-3500 3225);
FORCEPROP 2 LASTPIN (-3625 3975) $PN 41
J 2
(-3635 3985);
DISPLAY 0.617021 (-3635 3985);
PAINT MONO (-3635 3985);
FORCEPROP 2 LASTPIN (-3625 3575) $PN 32
J 2
(-3635 3585);
DISPLAY 0.617021 (-3635 3585);
PAINT MONO (-3635 3585);
FORCEPROP 2 LASTPIN (-3625 3725) $PN 39
J 2
(-3635 3735);
DISPLAY 0.617021 (-3635 3735);
PAINT MONO (-3635 3735);
FORCEPROP 1 LAST MATERIAL IC
J 0
(-3575 4675);
DISPLAY 0.617021 (-3575 4675);
PAINT SKYBLUE (-3575 4675);
FORCEPROP 2 LASTPIN (-3625 4375) $PN 25
J 2
(-3635 4385);
DISPLAY 0.617021 (-3635 4385);
PAINT MONO (-3635 4385);
FORCEPROP 2 LASTPIN (-3625 4425) $PN 30
J 2
(-3635 4435);
DISPLAY 0.617021 (-3635 4435);
PAINT MONO (-3635 4435);
FORCEPROP 2 LASTPIN (-3625 4475) $PN 3
J 2
(-3635 4485);
DISPLAY 0.617021 (-3635 4485);
PAINT MONO (-3635 4485);
FORCEPROP 2 LASTPIN (-2625 4275) $PN 37
J 0
(-2615 4285);
DISPLAY 0.617021 (-2615 4285);
PAINT MONO (-2615 4285);
FORCEPROP 2 LASTPIN (-2625 3975) $PN 36
J 0
(-2615 3985);
DISPLAY 0.617021 (-2615 3985);
PAINT MONO (-2615 3985);
FORCEPROP 2 LASTPIN (-2625 3625) $PN 10
J 0
(-2615 3635);
DISPLAY 0.617021 (-2615 3635);
PAINT MONO (-2615 3635);
FORCEPROP 2 LASTPIN (-2625 3425) $PN 7
J 0
(-2615 3435);
DISPLAY 0.617021 (-2615 3435);
PAINT MONO (-2615 3435);
FORCEPROP 2 LASTPIN (-3625 4175) $PN 35
J 2
(-3635 4185);
DISPLAY 0.617021 (-3635 4185);
PAINT MONO (-3635 4185);
FORCEPROP 2 LASTPIN (-3625 4275) $PN 4
J 2
(-3635 4285);
DISPLAY 0.617021 (-3635 4285);
PAINT MONO (-3635 4285);
FORCEPROP 2 LASTPIN (-3625 3625) $PN 33
J 2
(-3635 3635);
DISPLAY 0.617021 (-3635 3635);
PAINT MONO (-3635 3635);
FORCEPROP 2 LASTPIN (-2625 3375) $PN 5
J 0
(-2615 3385);
DISPLAY 0.617021 (-2615 3385);
PAINT MONO (-2615 3385);
FORCEPROP 2 LASTPIN (-2625 3475) $PN 40
J 0
(-2615 3485);
DISPLAY 0.617021 (-2615 3485);
PAINT MONO (-2615 3485);
FORCEPROP 1 LAST VALUE IR35411
J 1
(-3125 4550);
DISPLAY 0.617021 (-3125 4550);
PAINT SKYBLUE (-3125 4550);
DISPLAY INVISIBLE (-3125 4550);
FORCEPROP 2 LAST CDS_LIB mstr_discrete
J 0
(-3125 3925);
PAINT ORANGE (-3125 3925);
DISPLAY INVISIBLE (-3125 3925);
FORCEPROP 1 LAST PACK_TYPE SM
J 0
(-3575 4775);
PAINT SKYBLUE (-3575 4775);
DISPLAY INVISIBLE (-3575 4775);
FORCEPROP 2 LAST CDS_SEC 1
J 0
(-3575 4775);
PAINT MONO (-3575 4775);
DISPLAY INVISIBLE (-3575 4775);
FORCEPROP 2 LAST $SEC 1
J 0
(-3575 4775);
PAINT MONO (-3575 4775);
DISPLAY INVISIBLE (-3575 4775);
FORCEPROP 2 LAST CDS_LOCATION EU4C2
J 0
(-3575 4725);
PAINT GREEN (-3575 4725);
DISPLAY INVISIBLE (-3575 4725);
FORCEPROP 1 LAST PATH I71
J 0
(-3125 4675);
PAINT GREEN (-3125 4675);
DISPLAY INVISIBLE (-3125 4675);
FORCEADD GND..1
(-400 2900);
FORCEPROP 3 LASTPIN (-400 2950) SIG_NAME GND\g
J 0
(-390 2960);
DISPLAY 0.659574 (-390 2960);
PAINT MONO (-390 2960);
DISPLAY INVISIBLE (-390 2960);
FORCEPROP 1 LAST HDL_POWER GND
J 0
(-400 3050);
DISPLAY 1.723404 (-400 3050);
PAINT GREEN (-400 3050);
DISPLAY INVISIBLE (-400 3050);
FORCEPROP 2 LAST CDS_LIB mstr_symbols
J 0
(-400 2900);
DISPLAY 1.936170 (-400 2900);
PAINT ORANGE (-400 2900);
DISPLAY INVISIBLE (-400 2900);
FORCEPROP 1 LAST SIZE 1B
J 0
(-325 2850);
DISPLAY 1.723404 (-325 2850);
PAINT GREEN (-325 2850);
DISPLAY INVISIBLE (-325 2850);
FORCEPROP 1 LAST VOLTAGE 0
J 0
(-400 2900);
PAINT SKYBLUE (-400 2900);
DISPLAY INVISIBLE (-400 2900);
FORCEPROP 1 LAST BODY_TYPE PLUMBING
J 0
(-445 2857);
DISPLAY 0.340426 (-445 2857);
PAINT GREEN (-445 2857);
DISPLAY INVISIBLE (-445 2857);
FORCEPROP 1 LAST PATH I8
J 0
(-325 2900);
DISPLAY 0.872340 (-325 2900);
PAINT AQUA (-325 2900);
DISPLAY INVISIBLE (-325 2900);
FORCEPROP 2 LAST BOM_COST PROC_VRD_VCCIN_CPU0
J 0
(-775 2975);
DISPLAY 1.446809 (-775 2975);
PAINT MONO (-775 2975);
DISPLAY INVISIBLE (-775 2975);
FORCEPROP 2 LAST ROOM PVCCIN_CPU0_PWR_VR
J 0
(-950 2975);
DISPLAY 1.936170 (-950 2975);
PAINT ORANGE (-950 2975);
DISPLAY INVISIBLE (-950 2975);
FORCEADD RES..2
(-400 4075);
FORCEPROP 1 LAST TOLERANCE 1%
J 0
(-355 4100);
DISPLAY 0.617021 (-355 4100);
PAINT SKYBLUE (-355 4100);
FORCEPROP 1 LAST VALUE 68.1K
J 0
(-355 4150);
DISPLAY 0.617021 (-355 4150);
PAINT SKYBLUE (-355 4150);
FORCEPROP 1 LASTPIN (-400 4175) $PN 1
J 0
(-395 4137);
DISPLAY 0.617021 (-395 4137);
PAINT ORANGE (-395 4137);
FORCEPROP 1 LAST LOCATION R4D68
J 0
(-355 4200);
DISPLAY 0.617021 (-355 4200);
PAINT AQUA (-355 4200);
FORCEPROP 1 LASTPIN (-400 3975) $PN 2
J 0
(-395 3985);
DISPLAY 0.617021 (-395 3985);
PAINT ORANGE (-395 3985);
FORCEPROP 1 LAST PACK_TYPE 0402
J 0
(-360 3900);
DISPLAY 0.617021 (-360 3900);
PAINT SKYBLUE (-360 3900);
FORCEPROP 1 LAST WATTAGE 1/16W
J 0
(-360 4050);
DISPLAY 0.617021 (-360 4050);
PAINT SKYBLUE (-360 4050);
FORCEPROP 1 LAST MATERIAL EMPTY
J 0
(-360 4000);
DISPLAY 0.617021 (-360 4000);
PAINT RED (-360 4000);
FORCEPROP 1 LAST PART_NUMBER G21796-187
J 0
(-360 3950);
DISPLAY 0.617021 (-360 3950);
PAINT BLUE (-360 3950);
FORCEPROP 2 LAST CDS_LIB mstr_discrete
J 0
(-400 4075);
PAINT ORANGE (-400 4075);
DISPLAY INVISIBLE (-400 4075);
FORCEPROP 1 LAST PATH I83
J 0
(-350 4250);
DISPLAY 0.978723 (-350 4250);
PAINT WHITE (-350 4250);
DISPLAY INVISIBLE (-350 4250);
FORCEPROP 0 LAST SEC 1
J 0
(-350 4250);
DISPLAY 0.680851 (-350 4250);
PAINT MONO (-350 4250);
DISPLAY INVISIBLE (-350 4250);
FORCEPROP 2 LAST SEC_TYPE 0402
J 0
(-350 4300);
DISPLAY 1.021277 (-350 4300);
PAINT ORANGE (-350 4300);
DISPLAY INVISIBLE (-350 4300);
FORCEADD GND..1
(-400 3850);
FORCEPROP 3 LASTPIN (-400 3900) SIG_NAME GND\g
J 0
(-390 3910);
DISPLAY 0.659574 (-390 3910);
PAINT MONO (-390 3910);
DISPLAY INVISIBLE (-390 3910);
FORCEPROP 2 LAST ROOM PVCCIN_CPU0_PWR_VR
J 0
(-950 3925);
DISPLAY 1.936170 (-950 3925);
PAINT ORANGE (-950 3925);
DISPLAY INVISIBLE (-950 3925);
FORCEPROP 2 LAST BOM_COST PROC_VRD_VCCIN_CPU0
J 0
(-775 3925);
DISPLAY 1.446809 (-775 3925);
PAINT MONO (-775 3925);
DISPLAY INVISIBLE (-775 3925);
FORCEPROP 1 LAST BODY_TYPE PLUMBING
J 0
(-445 3807);
DISPLAY 0.340426 (-445 3807);
PAINT GREEN (-445 3807);
DISPLAY INVISIBLE (-445 3807);
FORCEPROP 1 LAST SIZE 1B
J 0
(-325 3800);
DISPLAY 1.723404 (-325 3800);
PAINT GREEN (-325 3800);
DISPLAY INVISIBLE (-325 3800);
FORCEPROP 2 LAST CDS_LIB mstr_symbols
J 0
(-400 3850);
PAINT ORANGE (-400 3850);
DISPLAY INVISIBLE (-400 3850);
FORCEPROP 1 LAST VOLTAGE 0
J 0
(-400 3850);
PAINT SKYBLUE (-400 3850);
DISPLAY INVISIBLE (-400 3850);
FORCEPROP 1 LAST HDL_POWER GND
J 0
(-400 4000);
DISPLAY 1.723404 (-400 4000);
PAINT GREEN (-400 4000);
DISPLAY INVISIBLE (-400 4000);
FORCEPROP 1 LAST PATH I84
J 0
(-325 3850);
DISPLAY 0.872340 (-325 3850);
PAINT AQUA (-325 3850);
DISPLAY INVISIBLE (-325 3850);
FORCEADD CAP_A..1
(-3850 3425);
FORCEPROP 1 LAST VOLTAGE 16V
J 0
(-3800 3425);
DISPLAY 0.617021 (-3800 3425);
PAINT SKYBLUE (-3800 3425);
FORCEPROP 1 LAST PART_NUMBER A36096-030
J 0
(-3800 3275);
DISPLAY 0.617021 (-3800 3275);
PAINT BLUE (-3800 3275);
FORCEPROP 0 LAST POP NOPOP
J 0
(-3800 3150);
DISPLAY 1.021277 (-3800 3150);
PAINT RED (-3800 3150);
FORCEPROP 1 LAST TOLERANCE 10%
J 0
(-3800 3375);
DISPLAY 0.617021 (-3800 3375);
PAINT SKYBLUE (-3800 3375);
FORCEPROP 1 LAST MATERIAL X7R
J 0
(-3800 3325);
DISPLAY 0.617021 (-3800 3325);
PAINT SKYBLUE (-3800 3325);
FORCEPROP 1 LASTPIN (-3850 3325) $PN 2
J 0
(-3840 3305);
DISPLAY 0.787234 (-3840 3305);
PAINT ORANGE (-3840 3305);
FORCEPROP 1 LAST PACK_TYPE 0402V
J 0
(-3800 3225);
DISPLAY 0.617021 (-3800 3225);
PAINT SKYBLUE (-3800 3225);
FORCEPROP 1 LAST VALUE 0.1UF
J 0
(-3800 3475);
DISPLAY 0.617021 (-3800 3475);
PAINT SKYBLUE (-3800 3475);
FORCEPROP 1 LAST LOCATION CT36
J 0
(-4000 3425);
DISPLAY 0.617021 (-4000 3425);
PAINT AQUA (-4000 3425);
FORCEPROP 1 LASTPIN (-3850 3525) $PN 1
J 0
(-3840 3505);
DISPLAY 0.787234 (-3840 3505);
PAINT ORANGE (-3840 3505);
FORCEPROP 2 LAST SEC_TYPE 0402V
J 0
(-3800 3625);
DISPLAY 1.021277 (-3800 3625);
PAINT ORANGE (-3800 3625);
DISPLAY INVISIBLE (-3800 3625);
FORCEPROP 0 LAST SEC 1
J 0
(-3800 3525);
DISPLAY 0.680851 (-3800 3525);
PAINT MONO (-3800 3525);
DISPLAY INVISIBLE (-3800 3525);
FORCEPROP 2 LAST ROOM PVCCIN_CPU0_PWR_VR
J 0
(-3800 3575);
DISPLAY 1.361702 (-3800 3575);
PAINT ORANGE (-3800 3575);
DISPLAY INVISIBLE (-3800 3575);
FORCEPROP 1 LAST PATH I85
J 0
(-3800 3575);
DISPLAY 0.978723 (-3800 3575);
PAINT WHITE (-3800 3575);
DISPLAY INVISIBLE (-3800 3575);
FORCEPROP 2 LAST CDS_LIB dev_discrete
J 0
(-3850 3425);
PAINT MONO (-3850 3425);
DISPLAY INVISIBLE (-3850 3425);
FORCEADD GND..1
(-3850 3175);
FORCEPROP 3 LASTPIN (-3850 3225) SIG_NAME GND\g
J 0
(-3840 3235);
DISPLAY 0.659574 (-3840 3235);
PAINT MONO (-3840 3235);
DISPLAY INVISIBLE (-3840 3235);
FORCEPROP 1 LAST BODY_TYPE PLUMBING
J 0
(-3895 3132);
DISPLAY 0.340426 (-3895 3132);
PAINT GREEN (-3895 3132);
DISPLAY INVISIBLE (-3895 3132);
FORCEPROP 2 LAST ROOM PVCCIN_CPU0_PWR_VR
J 0
(-4400 3250);
DISPLAY 1.936170 (-4400 3250);
PAINT ORANGE (-4400 3250);
DISPLAY INVISIBLE (-4400 3250);
FORCEPROP 2 LAST BOM_COST PROC_VRD_VCCIN_CPU0
J 0
(-4225 3250);
DISPLAY 1.446809 (-4225 3250);
PAINT MONO (-4225 3250);
DISPLAY INVISIBLE (-4225 3250);
FORCEPROP 1 LAST SIZE 1B
J 0
(-3775 3125);
DISPLAY 1.723404 (-3775 3125);
PAINT GREEN (-3775 3125);
DISPLAY INVISIBLE (-3775 3125);
FORCEPROP 1 LAST VOLTAGE 0
J 0
(-3850 3175);
PAINT SKYBLUE (-3850 3175);
DISPLAY INVISIBLE (-3850 3175);
FORCEPROP 1 LAST HDL_POWER GND
J 0
(-3850 3325);
DISPLAY 1.723404 (-3850 3325);
PAINT GREEN (-3850 3325);
DISPLAY INVISIBLE (-3850 3325);
FORCEPROP 1 LAST PATH I86
J 0
(-3775 3175);
DISPLAY 0.872340 (-3775 3175);
PAINT AQUA (-3775 3175);
DISPLAY INVISIBLE (-3775 3175);
FORCEPROP 2 LAST CDS_LIB mstr_symbols
J 0
(-3850 3175);
PAINT MONO (-3850 3175);
DISPLAY INVISIBLE (-3850 3175);
FORCEADD CAP..1
(-2075 3950);
FORCEPROP 1 LAST PACK_TYPE 0402LF
J 0
(-2025 3750);
DISPLAY 0.617021 (-2025 3750);
PAINT SKYBLUE (-2025 3750);
FORCEPROP 1 LASTPIN (-2075 3850) $PN 2
J 0
(-2065 3830);
DISPLAY 0.787234 (-2065 3830);
PAINT ORANGE (-2065 3830);
FORCEPROP 1 LASTPIN (-2075 4050) $PN 1
J 0
(-2065 4030);
DISPLAY 0.787234 (-2065 4030);
PAINT ORANGE (-2065 4030);
FORCEPROP 0 LAST POP NOPOP
J 0
(-1925 3925);
DISPLAY 1.021277 (-1925 3925);
PAINT RED (-1925 3925);
FORCEPROP 1 LAST LOCATION CT34
J 0
(-2025 4050);
DISPLAY 0.617021 (-2025 4050);
PAINT AQUA (-2025 4050);
FORCEPROP 1 LAST VALUE 1000PF
J 0
(-2025 4000);
DISPLAY 0.617021 (-2025 4000);
PAINT SKYBLUE (-2025 4000);
FORCEPROP 1 LAST VOLTAGE 50V
J 0
(-2025 3950);
DISPLAY 0.617021 (-2025 3950);
PAINT SKYBLUE (-2025 3950);
FORCEPROP 1 LAST TOLERANCE 10%
J 0
(-2025 3900);
DISPLAY 0.617021 (-2025 3900);
PAINT SKYBLUE (-2025 3900);
FORCEPROP 1 LAST MATERIAL X7R
J 0
(-2025 3850);
DISPLAY 0.617021 (-2025 3850);
PAINT SKYBLUE (-2025 3850);
FORCEPROP 1 LAST PART_NUMBER A36096-046
J 0
(-2025 3800);
DISPLAY 0.617021 (-2025 3800);
PAINT BLUE (-2025 3800);
FORCEPROP 2 LAST SEC_TYPE 0402LF
J 0
(-2025 4150);
DISPLAY 1.021277 (-2025 4150);
PAINT ORANGE (-2025 4150);
DISPLAY INVISIBLE (-2025 4150);
FORCEPROP 0 LAST SEC 1
J 0
(-2025 4100);
DISPLAY 0.680851 (-2025 4100);
PAINT MONO (-2025 4100);
DISPLAY INVISIBLE (-2025 4100);
FORCEPROP 0 LAST ROOM VDDQ_KLM_PWR_VR
J 0
(-2025 4150);
DISPLAY 1.021277 (-2025 4150);
PAINT ORANGE (-2025 4150);
DISPLAY INVISIBLE (-2025 4150);
FORCEPROP 1 LAST PATH I88
J 0
(-2025 4100);
DISPLAY 0.978723 (-2025 4100);
PAINT WHITE (-2025 4100);
DISPLAY INVISIBLE (-2025 4100);
FORCEPROP 2 LAST CDS_LIB mstr_discrete
J 0
(-2075 3950);
PAINT MONO (-2075 3950);
DISPLAY INVISIBLE (-2075 3950);
FORCEADD GND..1
(-2075 3750);
FORCEPROP 3 LASTPIN (-2075 3800) SIG_NAME GND\g
J 0
(-2065 3810);
DISPLAY 0.659574 (-2065 3810);
PAINT MONO (-2065 3810);
DISPLAY INVISIBLE (-2065 3810);
FORCEPROP 1 LAST HDL_POWER GND
J 0
(-2075 3900);
DISPLAY 1.170213 (-2075 3900);
PAINT GREEN (-2075 3900);
DISPLAY INVISIBLE (-2075 3900);
FORCEPROP 1 LAST SIZE 1B
J 0
(-2000 3700);
DISPLAY 1.170213 (-2000 3700);
PAINT AQUA (-2000 3700);
DISPLAY INVISIBLE (-2000 3700);
FORCEPROP 1 LAST BODY_TYPE PLUMBING
J 0
(-2120 3707);
DISPLAY 0.340426 (-2120 3707);
PAINT GREEN (-2120 3707);
DISPLAY INVISIBLE (-2120 3707);
FORCEPROP 1 LAST VOLTAGE 0
J 0
(-2075 3750);
PAINT SKYBLUE (-2075 3750);
DISPLAY INVISIBLE (-2075 3750);
FORCEPROP 2 LAST ROOM VDDQ_KLM_PWR_VR
J 0
(-2650 3825);
DISPLAY 1.361702 (-2650 3825);
PAINT ORANGE (-2650 3825);
DISPLAY INVISIBLE (-2650 3825);
FORCEPROP 1 LAST PATH I89
J 0
(-2000 3750);
DISPLAY 0.872340 (-2000 3750);
PAINT AQUA (-2000 3750);
DISPLAY INVISIBLE (-2000 3750);
FORCEPROP 2 LAST CDS_LIB mstr_symbols
J 0
(-2075 3750);
PAINT MONO (-2075 3750);
DISPLAY INVISIBLE (-2075 3750);
FORCEADD CAP_A..1
(-700 3425);
FORCEPROP 0 LAST GROUP PWR_MLCC_CAP
J 0
(-644 3212);
DISPLAY 0.638298 (-644 3212);
PAINT BROWN (-644 3212);
DISPLAY BOTH (-644 3212);
FORCEPROP 1 LAST MATERIAL X6S
J 0
(-650 3375);
DISPLAY 0.617021 (-650 3375);
PAINT SKYBLUE (-650 3375);
FORCEPROP 1 LAST LOCATION C4D12
J 0
(-650 3575);
DISPLAY 0.617021 (-650 3575);
PAINT AQUA (-650 3575);
FORCEPROP 1 LAST VALUE 22.0UF
J 0
(-650 3525);
DISPLAY 0.617021 (-650 3525);
PAINT SKYBLUE (-650 3525);
FORCEPROP 1 LAST VOLTAGE 4V
J 0
(-650 3475);
DISPLAY 0.617021 (-650 3475);
PAINT SKYBLUE (-650 3475);
FORCEPROP 1 LAST TOLERANCE 20%
J 0
(-650 3425);
DISPLAY 0.617021 (-650 3425);
PAINT SKYBLUE (-650 3425);
FORCEPROP 1 LAST PACK_TYPE 0603V
J 0
(-650 3275);
DISPLAY 0.617021 (-650 3275);
PAINT SKYBLUE (-650 3275);
FORCEPROP 1 LAST PART_NUMBER E15431-004
J 0
(-650 3325);
DISPLAY 0.617021 (-650 3325);
PAINT BLUE (-650 3325);
FORCEPROP 1 LASTPIN (-700 3525) $PN 1
J 0
(-690 3505);
DISPLAY 0.617021 (-690 3505);
PAINT GREEN (-690 3505);
FORCEPROP 1 LASTPIN (-700 3325) $PN 2
J 0
(-690 3305);
DISPLAY 0.617021 (-690 3305);
PAINT GREEN (-690 3305);
FORCEPROP 2 LAST CDS_LOCATION C4D12
J 0
(-650 3525);
DISPLAY 0.617021 (-650 3525);
PAINT AQUA (-650 3525);
DISPLAY INVISIBLE (-650 3525);
FORCEPROP 2 LAST BOM_COST PROC_VRD_VCCIN_CPU0
J 0
(-650 3575);
DISPLAY 1.446809 (-650 3575);
PAINT MONO (-650 3575);
DISPLAY INVISIBLE (-650 3575);
FORCEPROP 2 LAST CDS_LIB dev_discrete
J 0
(-700 3425);
PAINT ORANGE (-700 3425);
DISPLAY INVISIBLE (-700 3425);
FORCEPROP 2 LAST CDS_SEC 1
J 0
(-650 3575);
PAINT ORANGE (-650 3575);
DISPLAY INVISIBLE (-650 3575);
FORCEPROP 1 LAST PATH I9
J 0
(-650 3575);
DISPLAY 0.978723 (-650 3575);
PAINT WHITE (-650 3575);
DISPLAY INVISIBLE (-650 3575);
FORCEPROP 2 LAST ROOM PVCCIN_CPU0_PWR_VR
J 0
(-650 3575);
DISPLAY 1.446809 (-650 3575);
PAINT MONO (-650 3575);
DISPLAY INVISIBLE (-650 3575);
FORCEPROP 2 LAST SEC_TYPE 0603V
J 0
(-645 3625);
DISPLAY 1.021277 (-645 3625);
PAINT ORANGE (-645 3625);
DISPLAY INVISIBLE (-645 3625);
FORCEPROP 2 LAST SEC 1
J 0
(-645 3625);
DISPLAY 0.680851 (-645 3625);
PAINT MONO (-645 3625);
DISPLAY INVISIBLE (-645 3625);
FORCEADD GND..1
(-1975 2975);
FORCEPROP 3 LASTPIN (-1975 3025) SIG_NAME GND\g
J 0
(-1965 3035);
DISPLAY 0.659574 (-1965 3035);
PAINT MONO (-1965 3035);
DISPLAY INVISIBLE (-1965 3035);
FORCEPROP 2 LAST ROOM PVCCIN_CPU0_PWR_VR
J 0
(-2525 3050);
DISPLAY 1.936170 (-2525 3050);
PAINT ORANGE (-2525 3050);
DISPLAY INVISIBLE (-2525 3050);
FORCEPROP 2 LAST BOM_COST PROC_VRD_VCCIN_CPU0
J 0
(-2350 3050);
DISPLAY 1.446809 (-2350 3050);
PAINT MONO (-2350 3050);
DISPLAY INVISIBLE (-2350 3050);
FORCEPROP 1 LAST BODY_TYPE PLUMBING
J 0
(-2020 2932);
DISPLAY 0.340426 (-2020 2932);
PAINT GREEN (-2020 2932);
DISPLAY INVISIBLE (-2020 2932);
FORCEPROP 1 LAST VOLTAGE 0
J 0
(-1975 2975);
PAINT SKYBLUE (-1975 2975);
DISPLAY INVISIBLE (-1975 2975);
FORCEPROP 1 LAST SIZE 1B
J 0
(-1900 2925);
DISPLAY 1.723404 (-1900 2925);
PAINT GREEN (-1900 2925);
DISPLAY INVISIBLE (-1900 2925);
FORCEPROP 1 LAST HDL_POWER GND
J 0
(-1975 3125);
DISPLAY 1.723404 (-1975 3125);
PAINT GREEN (-1975 3125);
DISPLAY INVISIBLE (-1975 3125);
FORCEPROP 1 LAST PATH I92
J 0
(-1900 2975);
DISPLAY 0.872340 (-1900 2975);
PAINT AQUA (-1900 2975);
DISPLAY INVISIBLE (-1900 2975);
FORCEPROP 2 LAST CDS_LIB mstr_symbols
J 0
(-1975 2975);
PAINT MONO (-1975 2975);
DISPLAY INVISIBLE (-1975 2975);
FORCEADD CAP..1
(-1975 3475);
FORCEPROP 1 LAST MATERIAL X7R
J 0
(-1775 3550);
DISPLAY 0.617021 (-1775 3550);
PAINT SKYBLUE (-1775 3550);
FORCEPROP 1 LAST VALUE 1000PF
J 0
(-1925 3525);
DISPLAY 0.617021 (-1925 3525);
PAINT SKYBLUE (-1925 3525);
FORCEPROP 1 LAST TOLERANCE 10%
J 0
(-1925 3425);
DISPLAY 0.617021 (-1925 3425);
PAINT SKYBLUE (-1925 3425);
FORCEPROP 1 LAST LOCATION CT35
J 0
(-1925 3575);
DISPLAY 0.617021 (-1925 3575);
PAINT AQUA (-1925 3575);
FORCEPROP 1 LAST PART_NUMBER A36096-046
J 0
(-1775 3500);
DISPLAY 0.617021 (-1775 3500);
PAINT BLUE (-1775 3500);
FORCEPROP 1 LAST PACK_TYPE 0402LF
J 0
(-1725 3450);
DISPLAY 0.617021 (-1725 3450);
PAINT SKYBLUE (-1725 3450);
FORCEPROP 0 LAST POP NOPOP
J 0
(-1575 3550);
DISPLAY 0.808511 (-1575 3550);
PAINT RED (-1575 3550);
FORCEPROP 1 LASTPIN (-1975 3575) $PN 1
J 0
(-1965 3555);
DISPLAY 0.787234 (-1965 3555);
PAINT ORANGE (-1965 3555);
FORCEPROP 1 LASTPIN (-1975 3375) $PN 2
J 0
(-1965 3355);
DISPLAY 0.787234 (-1965 3355);
PAINT ORANGE (-1965 3355);
FORCEPROP 1 LAST VOLTAGE 50V
J 0
(-1925 3475);
DISPLAY 0.617021 (-1925 3475);
PAINT SKYBLUE (-1925 3475);
FORCEPROP 2 LAST SEC_TYPE 0402LF
J 0
(-1925 3675);
DISPLAY 1.021277 (-1925 3675);
PAINT ORANGE (-1925 3675);
DISPLAY INVISIBLE (-1925 3675);
FORCEPROP 0 LAST SEC 1
J 0
(-1925 3625);
DISPLAY 0.680851 (-1925 3625);
PAINT MONO (-1925 3625);
DISPLAY INVISIBLE (-1925 3625);
FORCEPROP 0 LAST ROOM VDDQ_KLM_PWR_VR
J 0
(-1925 3675);
DISPLAY 1.021277 (-1925 3675);
PAINT ORANGE (-1925 3675);
DISPLAY INVISIBLE (-1925 3675);
FORCEPROP 1 LAST PATH I97
J 0
(-1925 3625);
DISPLAY 0.978723 (-1925 3625);
PAINT WHITE (-1925 3625);
DISPLAY INVISIBLE (-1925 3625);
FORCEPROP 2 LAST CDS_LIB mstr_discrete
J 0
(-1975 3475);
PAINT MONO (-1975 3475);
DISPLAY INVISIBLE (-1975 3475);
FORCEADD RES..1
(-4875 3725);
FORCEPROP 1 LAST TOLERANCE 5.0%
J 0
(-4675 3625);
DISPLAY 0.617021 (-4675 3625);
PAINT SKYBLUE (-4675 3625);
FORCEPROP 1 LAST MATERIAL CHIP
J 0
(-4650 3575);
DISPLAY 0.617021 (-4650 3575);
PAINT SKYBLUE (-4650 3575);
FORCEPROP 1 LAST PART_NUMBER G22178-002
J 0
(-5050 3625);
DISPLAY 0.617021 (-5050 3625);
PAINT BLUE (-5050 3625);
FORCEPROP 1 LASTPIN (-4775 3725) $PN 2
J 0
(-4813 3737);
DISPLAY 0.787234 (-4813 3737);
PAINT ORANGE (-4813 3737);
FORCEPROP 1 LAST VALUE 0
J 2
(-4925 3675);
DISPLAY 0.617021 (-4925 3675);
PAINT SKYBLUE (-4925 3675);
FORCEPROP 1 LAST LOCATION RT23
J 0
(-4975 3575);
DISPLAY 0.617021 (-4975 3575);
PAINT AQUA (-4975 3575);
FORCEPROP 1 LASTPIN (-4975 3725) $PN 1
J 0
(-4963 3737);
DISPLAY 0.787234 (-4963 3737);
PAINT ORANGE (-4963 3737);
FORCEPROP 1 LAST WATTAGE 1/10W
J 0
(-4500 3575);
DISPLAY 0.617021 (-4500 3575);
PAINT SKYBLUE (-4500 3575);
FORCEPROP 1 LAST PACK_TYPE 0603
J 0
(-4800 3675);
DISPLAY 0.617021 (-4800 3675);
PAINT SKYBLUE (-4800 3675);
FORCEPROP 2 LAST SEC_TYPE 0603
J 0
(-4925 3925);
DISPLAY 1.021277 (-4925 3925);
PAINT ORANGE (-4925 3925);
DISPLAY INVISIBLE (-4925 3925);
FORCEPROP 0 LAST SEC 1
J 0
(-5125 3825);
DISPLAY 0.680851 (-5125 3825);
PAINT MONO (-5125 3825);
DISPLAY INVISIBLE (-5125 3825);
FORCEPROP 0 LAST ROOM NIC_SPRV
J 0
(-4775 3850);
DISPLAY 1.021277 (-4775 3850);
PAINT ORANGE (-4775 3850);
DISPLAY INVISIBLE (-4775 3850);
FORCEPROP 0 LAST BOM_COST NT_GBE_BASE
J 0
(-4775 3950);
DISPLAY 1.021277 (-4775 3950);
PAINT ORANGE (-4775 3950);
DISPLAY INVISIBLE (-4775 3950);
FORCEPROP 1 LAST PATH I99
J 0
(-4925 3875);
DISPLAY 0.978723 (-4925 3875);
PAINT WHITE (-4925 3875);
DISPLAY INVISIBLE (-4925 3875);
FORCEPROP 2 LAST CDS_LIB mstr_discrete
J 0
(-4875 3725);
PAINT MONO (-4875 3725);
DISPLAY INVISIBLE (-4875 3725);
FORCEADD DNS..2
(-395 4070);
PAINT RED (-395 4070);
FORCEPROP 1 LAST COMMENT_BODY TRUE
R 1
J 0
(-320 3845);
DISPLAY 0.872340 (-320 3845);
PAINT GREEN (-320 3845);
DISPLAY INVISIBLE (-320 3845);
FORCEPROP 2 LAST CDS_LIB mstr_misc
J 0
(-395 4070);
PAINT ORANGE (-395 4070);
DISPLAY INVISIBLE (-395 4070);
FORCEADD DNS..2
(-6270 1620);
PAINT RED (-6270 1620);
FORCEPROP 2 LAST CDS_LIB mstr_misc
J 0
(-6270 1620);
PAINT ORANGE (-6270 1620);
DISPLAY INVISIBLE (-6270 1620);
FORCEPROP 1 LAST COMMENT_BODY TRUE
R 1
J 0
(-6195 1395);
DISPLAY 0.872340 (-6195 1395);
PAINT GREEN (-6195 1395);
DISPLAY INVISIBLE (-6195 1395);
FORCEADD INTEL_CORP_BPAGE..1
(0 0);
FORCEPROP 1 LAST CDS_CON_LAST_MODIFIED Fri Jun 16 17:49:14 2017
J 0
(-1425 325);
PAINT ORANGE (-1425 325);
DISPLAY INVISIBLE (-1425 325);
FORCEPROP 1 LAST CUSTOM_TXT_CDS <CURRENT_DESIGN_SHEET> OF <TOTAL_DESIGN_SHEETS>
J 0
(-500 25);
PAINT ORANGE (-500 25);
FORCEPROP 1 LAST CUSTOM_TXT_CDS <CON_LAST_MODIFIED>
J 0
(-4000 100);
PAINT ORANGE (-4000 100);
FORCEPROP 2 LAST CUSTOM_TXT_CDS <XR_PAGE_TITLE>
J 0
(-7890 5250);
DISPLAY 0.638298 (-7890 5250);
PAINT PINK (-7890 5250);
DISPLAY INVISIBLE (-7890 5250);
FORCEPROP 1 LAST SCH_TITLE VCCIN CPU0 (4 OF 4)
J 0
(-7950 50);
DISPLAY 1.212766 (-7950 50);
PAINT ORANGE (-7950 50);
FORCEPROP 1 LAST COMMENT_BODY TRUE
J 0
(12 12);
DISPLAY 0.468085 (12 12);
PAINT GREEN (12 12);
DISPLAY INVISIBLE (12 12);
FORCEPROP 2 LAST CDS_LIB mstr_symbols
J 0
(0 0);
PAINT MONO (0 0);
DISPLAY INVISIBLE (0 0);
FORCEPROP 2 LAST PAGE_BORDER TRUE
J 0
(-7890 5250);
DISPLAY 0.638298 (-7890 5250);
PAINT PINK (-7890 5250);
DISPLAY INVISIBLE (-7890 5250);
FORCEPROP 2 LAST CDS_XR_PAGE_TITLE CR-204 : @BASEBOARD_FAB2_LIB.BASEBOARD_FAB2(SCH_1):PAGE204
J 0
(-7890 5250);
DISPLAY 0.638298 (-7890 5250);
PAINT PINK (-7890 5250);
DISPLAY INVISIBLE (-7890 5250);
FORCEADD DESIGN_NOTE..1
(-7625 2550);
PAINT PURPLE (-7625 2550);
FORCEPROP 2 LAST BOM_COST SM_CONTROLLER
J 0
(-7825 2500);
PAINT MONO (-7825 2500);
DISPLAY INVISIBLE (-7825 2500);
FORCEPROP 2 LAST ROOM PVCCIN_CPU0_VR
J 0
(-7825 2500);
PAINT MONO (-7825 2500);
DISPLAY INVISIBLE (-7825 2500);
FORCEPROP 2 LAST CDS_LIB mstr_symbols
J 0
(-7625 2550);
PAINT ORANGE (-7625 2550);
DISPLAY INVISIBLE (-7625 2550);
FORCEPROP 1 LAST COMMENT_BODY TRUE
J 0
(-7600 2650);
DISPLAY 1.319149 (-7600 2650);
PAINT GREEN (-7600 2650);
DISPLAY INVISIBLE (-7600 2650);
WIRE 16 -1 (-2475 3325)(-2475 3375);
WIRE 16 -1 (-2475 3375)(-2475 3425);
WIRE 16 -1 (-2475 3375)(-2625 3375);
WIRE 16 -1 (-2475 3425)(-2475 3475);
WIRE 16 -1 (-2475 3425)(-2625 3425);
WIRE 16 -1 (-2475 3475)(-2475 3525);
WIRE 16 -1 (-2475 3475)(-2625 3475);
WIRE 16 -1 (-2625 3525)(-2475 3525);
WIRE 16 -1 (-400 3625)(-400 3675);
WIRE 16 -1 (-400 3625)(-700 3625);
WIRE 16 -1 (-400 3525)(-400 3625);
WIRE 16 -1 (-875 3625)(-700 3625);
WIRE 16 -1 (-700 3525)(-700 3625);
WIRE 16 -1 (-875 2900)(-875 3625);
WIRE 16 -1 (-900 3625)(-875 3625);
WIRE 16 -1 (-3725 2900)(-875 2900);
WIRE 16 -1 (-3725 4075)(-3725 2900);
WIRE 16 -1 (-3625 4075)(-3725 4075);
WIRE 16 -1 (-6675 4600)(-6675 4425);
WIRE 16 -1 (-6675 4425)(-6600 4425);
WIRE 16 -1 (-6675 4425)(-6900 4425);
WIRE 16 -1 (-7200 4425)(-6900 4425);
WIRE 16 -1 (-6900 4275)(-6900 4425);
WIRE 16 -1 (-6300 4425)(-6600 4425);
WIRE 16 -1 (-6600 4275)(-6600 4425);
WIRE 16 -1 (-6300 4425)(-6000 4425);
WIRE 16 -1 (-6300 4275)(-6300 4425);
WIRE 16 -1 (-7200 4275)(-7200 4425);
WIRE 16 -1 (-3725 4425)(-6000 4425);
WIRE 16 -1 (-6000 4275)(-6000 4425);
WIRE 16 -1 (-3725 4425)(-3725 4375);
WIRE 16 -1 (-3625 4425)(-3725 4425);
WIRE 16 -1 (-3625 4375)(-3725 4375);
WIRE 16 -1 (-7025 3775)(-7025 3875);
WIRE 16 -1 (-7025 3875)(-6900 3875);
WIRE 16 -1 (-7025 3875)(-7200 3875);
WIRE 16 -1 (-7200 4075)(-7200 3875);
WIRE 16 -1 (-6900 3875)(-6600 3875);
WIRE 16 -1 (-6900 4075)(-6900 3875);
WIRE 16 -1 (-6300 3875)(-6600 3875);
WIRE 16 -1 (-6600 4075)(-6600 3875);
WIRE 16 -1 (-6300 3875)(-6000 3875);
WIRE 16 -1 (-6300 4075)(-6300 3875);
WIRE 16 -1 (-6000 3875)(-5700 3875);
WIRE 16 -1 (-6000 4075)(-6000 3875);
WIRE 16 -1 (-5200 3875)(-5700 3875);
WIRE 16 -1 (-5700 4075)(-5700 3875);
WIRE 16 -1 (-4875 3875)(-5200 3875);
WIRE 16 -1 (-5200 4075)(-5200 3875);
WIRE 16 -1 (-4875 4100)(-4875 3875);
WIRE 16 -1 (-575 2400)(-575 2175);
WIRE 16 -1 (-575 2175)(-925 2175);
WIRE 16 -1 (-575 2075)(-575 2175);
WIRE 16 -1 (-1400 2175)(-925 2175);
WIRE 16 -1 (-925 2075)(-925 2175);
WIRE 16 -1 (-1400 2100)(-1400 2175);
WIRE 16 -1 (-1400 2175)(-2875 2175);
WIRE 16 -1 (-1175 1625)(-1175 1700);
WIRE 16 -1 (-925 1700)(-1175 1700);
WIRE 16 -1 (-1175 1700)(-1400 1700);
WIRE 16 -1 (-1400 1900)(-1400 1700);
WIRE 16 -1 (-575 1700)(-925 1700);
WIRE 16 -1 (-925 1875)(-925 1700);
WIRE 16 -1 (-575 1875)(-575 1700);
WIRE 16 -1 (-4625 2225)(-4625 2325);
WIRE 16 -1 (-5375 2225)(-4625 2225);
WIRE 16 -1 (-4800 750)(-4800 975);
WIRE 16 -1 (-4800 975)(-5350 975);
WIRE 16 -1 (-3325 2375)(-3325 2175);
WIRE 16 -1 (-3325 2175)(-3175 2175);
WIRE 16 -1 (-4675 4750)(-4675 4825);
WIRE 16 -1 (-4675 4275)(-4675 4750);
WIRE 16 -1 (-4675 4750)(-4875 4750);
WIRE 16 -1 (-4875 4750)(-5200 4750);
WIRE 16 -1 (-4875 4300)(-4875 4750);
WIRE 16 -1 (-3725 4275)(-4675 4275);
WIRE 16 -1 (-3725 4175)(-3725 4275);
WIRE 16 -1 (-3625 4275)(-3725 4275);
WIRE 16 -1 (-5200 4225)(-5200 4750);
WIRE 16 -1 (-5450 4750)(-5200 4750);
WIRE 16 -1 (-3625 4175)(-3725 4175);
WIRE 16 -1 (-400 2950)(-400 3050);
WIRE 16 -1 (-400 3050)(-700 3050);
WIRE 16 -1 (-400 3325)(-400 3050);
WIRE 16 -1 (-700 3325)(-700 3050);
WIRE 16 -1 (-400 3975)(-400 3900);
WIRE 16 -1 (-3850 3325)(-3850 3225);
WIRE 16 -1 (-2075 3800)(-2075 3850);
WIRE 16 -1 (-1975 3050)(-1975 3025);
WIRE 16 -1 (-7550 1775)(-6825 1775);
FORCEPROP 2 LAST SIG_NAME VSENSE_PVCCIN_CPU0_P
J 0
(-7560 1785);
DISPLAY 0.617021 (-7560 1785);
PAINT ORANGE (-7560 1785);
WIRE 16 -1 (-6825 1675)(-6825 1775);
WIRE 16 -1 (-6825 1675)(-6500 1675);
WIRE 16 -1 (-6500 1675)(-6500 1825);
WIRE 16 -1 (-6500 1825)(-6275 1825);
WIRE 16 -1 (-6275 1725)(-6275 1825);
WIRE 16 -1 (-5850 2225)(-5575 2225);
WIRE 16 -1 (-5850 1825)(-6275 1825);
WIRE 16 -1 (-5575 1825)(-5850 1825);
WIRE 16 -1 (-5850 1825)(-5850 2225);
WIRE 16 273 (-6850 1325)(-6850 1925);
WIRE 16 273 (-6425 1325)(-6850 1325);
WIRE 16 273 (-6850 1925)(-6425 1925);
WIRE 16 273 (-6425 1925)(-6425 1325);
WIRE 16 682 (-7150 1875)(-7850 1875);
WIRE 16 682 (-7150 2625)(-7150 1875);
WIRE 16 682 (-7850 1875)(-7850 2625);
WIRE 16 682 (-7850 2625)(-7150 2625);
WIRE 16 2175 (-6175 3775)(-6175 3325);
WIRE 16 2175 (-6175 3325)(-5225 3325);
WIRE 16 2175 (-6175 3775)(-5225 3775);
WIRE 16 2175 (-5225 3775)(-5225 3325);
WIRE 16 2175 (-5375 3975)(-4725 3975);
WIRE 16 2175 (-4725 4350)(-4725 3975);
WIRE 16 2175 (-5375 4350)(-5375 3975);
WIRE 16 2175 (-5375 4350)(-4725 4350);
WIRE 16 -1 (-4100 3575)(-3625 3575);
WIRE 16 -1 (-4100 3450)(-4100 3575);
WIRE 16 -1 (-5825 3450)(-5825 3475);
WIRE 16 -1 (-5825 3450)(-4100 3450);
FORCEPROP 0 LAST VOLTAGE 5
J 0
(-5725 3525);
DISPLAY 1.021277 (-5725 3525);
PAINT SKYBLUE (-5725 3525);
DISPLAY INVISIBLE (-5725 3525);
FORCEPROP 2 LAST SIG_NAME VR_PVCCIN_CPU0_PH5_PHASE
J 0
(-5746 3460);
DISPLAY 0.617021 (-5746 3460);
PAINT ORANGE (-5746 3460);
FORCEPROP 2 LASTPROP $XRERR UNIQUE?
J 0
(-5986 3460);
DISPLAY 0.638298 (-5986 3460);
PAINT MONO (-5986 3460);
DISPLAY INVISIBLE (-5986 3460);
WIRE 16 -1 (-3850 3525)(-3850 3725);
WIRE 16 -1 (-3625 3725)(-3850 3725);
WIRE 16 -1 (-3850 3725)(-3850 4800);
WIRE 16 -1 (-3850 4800)(-1100 4800);
FORCEPROP 2 LAST SIG_NAME VR_PVCCIN_CPU0_AIREF5
J 0
(-1626 4808);
DISPLAY 0.617021 (-1626 4808);
PAINT ORANGE (-1626 4808);
WIRE 16 -1 (-5700 4750)(-5650 4750);
WIRE 16 -1 (-5700 4275)(-5700 4475);
WIRE 16 -1 (-5700 4750)(-5700 4475);
WIRE 16 -1 (-5700 4475)(-3625 4475);
FORCEPROP 0 LAST VOLTAGE 5
J 0
(-4225 4550);
DISPLAY 1.021277 (-4225 4550);
PAINT SKYBLUE (-4225 4550);
DISPLAY INVISIBLE (-4225 4550);
FORCEPROP 2 LAST SIG_NAME VR_PVCCIN_CPU0_PH5_VCIN
J 0
(-4586 4485);
DISPLAY 0.617021 (-4586 4485);
PAINT ORANGE (-4586 4485);
FORCEPROP 2 LASTPROP $XRERR UNIQUE?
J 0
(-4826 4485);
DISPLAY 0.638298 (-4826 4485);
PAINT MONO (-4826 4485);
DISPLAY INVISIBLE (-4826 4485);
WIRE 16 -1 (-4600 3925)(-3625 3925);
FORCEPROP 0 LAST SIG_NAME TP_PVCCIN_CPU0_PH5_GL_0
J 0
(-4573 3940);
DISPLAY 0.617021 (-4573 3940);
PAINT ORANGE (-4573 3940);
FORCEPROP 2 LASTPROP $XRERR UNIQUE?
J 0
(-4840 3925);
DISPLAY 0.638298 (-4840 3925);
PAINT MONO (-4840 3925);
DISPLAY INVISIBLE (-4840 3925);
WIRE 16 -1 (-6400 3825)(-3625 3825);
WIRE 3 682 (-5150 4000)(-5250 4000);
WIRE 3 682 (-5150 4300)(-5150 4000);
WIRE 3 682 (-5250 4000)(-5250 4300);
WIRE 3 682 (-5250 4300)(-5150 4300);
WIRE 3 2175 (-2050 2950)(-1250 2950);
WIRE 3 2175 (-1250 3675)(-1250 2950);
WIRE 3 2175 (-2050 3675)(-2050 2950);
WIRE 3 2175 (-2050 3675)(-1250 3675);
WIRE 16 -1 (-1975 3575)(-1975 3625);
WIRE 16 -1 (-1975 3625)(-1200 3625);
WIRE 16 -1 (-2625 3625)(-1975 3625);
FORCEPROP 0 LAST VOLTAGE 5
J 0
(-2175 3700);
DISPLAY 1.021277 (-2175 3700);
PAINT SKYBLUE (-2175 3700);
DISPLAY INVISIBLE (-2175 3700);
FORCEPROP 2 LAST SIG_NAME VR_PVCCIN_CPU0_PHASE5
J 0
(-2565 3635);
DISPLAY 0.617021 (-2565 3635);
PAINT ORANGE (-2565 3635);
FORCEPROP 2 LASTPROP $XRERR UNIQUE?
J 0
(-2805 3635);
DISPLAY 0.638298 (-2805 3635);
PAINT MONO (-2805 3635);
DISPLAY INVISIBLE (-2805 3635);
WIRE 3 2175 (-5725 4850)(-5375 4850);
WIRE 3 2175 (-5375 4850)(-5375 4600);
WIRE 3 2175 (-5725 4850)(-5725 4600);
WIRE 3 2175 (-5725 4600)(-5375 4600);
WIRE 3 2175 (-5100 3525)(-4700 3525);
WIRE 3 2175 (-4700 3800)(-4700 3525);
WIRE 3 2175 (-5100 3800)(-5100 3525);
WIRE 3 2175 (-5100 3800)(-4700 3800);
WIRE 16 -1 (-4100 3625)(-3625 3625);
WIRE 16 -1 (-4100 3725)(-4100 3625);
WIRE 16 -1 (-4775 3725)(-4100 3725);
FORCEPROP 2 LAST SIG_NAME VR_PVCCIN_CPU0_PH5_BOOT_R
J 0
(-4671 3735);
DISPLAY 0.617021 (-4671 3735);
PAINT ORANGE (-4671 3735);
FORCEPROP 2 LASTPROP $XRERR UNIQUE?
J 0
(-4911 3735);
DISPLAY 0.638298 (-4911 3735);
PAINT MONO (-4911 3735);
DISPLAY INVISIBLE (-4911 3735);
WIRE 3 682 (-3500 750)(-1550 750);
WIRE 3 682 (-3500 1700)(-3500 750);
WIRE 3 682 (-1550 750)(-1550 2400);
WIRE 3 682 (-2150 2400)(-1550 2400);
WIRE 3 682 (-2150 1700)(-3500 1700);
WIRE 3 682 (-2150 1700)(-2150 2400);
WIRE 16 -1 (-1975 3300)(-1975 3350);
WIRE 16 -1 (-1975 3350)(-1975 3375);
WIRE 16 -1 (-1300 3350)(-1975 3350);
FORCEPROP 2 LAST SIG_NAME VR_PVCCIN_CPU0_PHASE5_RC
J 0
(-1890 3360);
DISPLAY 0.617021 (-1890 3360);
PAINT ORANGE (-1890 3360);
FORCEPROP 2 LASTPROP $XRERR UNIQUE?
J 0
(-1270 3350);
DISPLAY 0.638298 (-1270 3350);
PAINT MONO (-1270 3350);
DISPLAY INVISIBLE (-1270 3350);
WIRE 3 2175 (-2150 3700)(-1700 3700);
WIRE 3 2175 (-1700 4175)(-1700 3700);
WIRE 3 2175 (-2150 4175)(-2150 3700);
WIRE 3 2175 (-2150 4175)(-1700 4175);
WIRE 16 -1 (-5825 3725)(-5825 3675);
WIRE 16 -1 (-5825 3725)(-4975 3725);
FORCEPROP 2 LAST SIG_NAME VR_PVCCIN_CPU0_PH5_BOOT
J 0
(-5796 3735);
DISPLAY 0.617021 (-5796 3735);
PAINT ORANGE (-5796 3735);
FORCEPROP 2 LASTPROP $XRERR UNIQUE?
J 0
(-6036 3735);
DISPLAY 0.638298 (-6036 3735);
PAINT MONO (-6036 3735);
DISPLAY INVISIBLE (-6036 3735);
WIRE 16 -1 (-4600 3975)(-3625 3975);
FORCEPROP 0 LAST SIG_NAME TP_PVCCIN_CPU0_PH5_GL_1
J 0
(-4573 3990);
DISPLAY 0.617021 (-4573 3990);
PAINT ORANGE (-4573 3990);
FORCEPROP 2 LASTPROP $XRERR UNIQUE?
J 0
(-4840 3975);
DISPLAY 0.638298 (-4840 3975);
PAINT MONO (-4840 3975);
DISPLAY INVISIBLE (-4840 3975);
WIRE 16 -1 (-2075 4050)(-2075 4125);
WIRE 16 -1 (-2075 4125)(-1550 4125);
WIRE 16 -1 (-2625 4125)(-2625 3975);
WIRE 16 -1 (-2625 4125)(-2075 4125);
FORCEPROP 2 LAST SIG_NAME A_TSENSE_PVCCIN_CPU0
J 0
(-2586 4135);
DISPLAY 0.617021 (-2586 4135);
PAINT ORANGE (-2586 4135);
WIRE 16 -1 (-2625 4475)(-1125 4475);
FORCEPROP 2 LAST SIG_NAME ISENSE_PVCCIN_CPU0_PH5_IMON
J 0
(-2515 4485);
DISPLAY 0.617021 (-2515 4485);
PAINT ORANGE (-2515 4485);
WIRE 3 682 (-2550 4225)(-2450 4225);
WIRE 16 -1 (-400 4175)(-400 4275);
WIRE 16 -1 (-2625 4275)(-400 4275);
FORCEPROP 0 LAST VOLTAGE 3.6
J 0
(-2550 4350);
DISPLAY 1.021277 (-2550 4350);
PAINT SKYBLUE (-2550 4350);
DISPLAY INVISIBLE (-2550 4350);
FORCEPROP 2 LAST SIG_NAME VR_PVCCIN_CPU0_PH5_OCSET
J 0
(-2543 4291);
DISPLAY 0.617021 (-2543 4291);
PAINT ORANGE (-2543 4291);
FORCEPROP 2 LASTPROP $XRERR UNIQUE?
J 0
(-2783 4291);
DISPLAY 0.638298 (-2783 4291);
PAINT MONO (-2783 4291);
DISPLAY INVISIBLE (-2783 4291);
WIRE 16 -1 (-5850 975)(-5550 975);
WIRE 16 -1 (-5850 1375)(-5850 975);
WIRE 16 -1 (-5550 1375)(-5850 1375);
WIRE 16 -1 (-6275 1525)(-6275 1375);
WIRE 16 -1 (-5850 1375)(-6275 1375);
WIRE 16 -1 (-6500 1375)(-6275 1375);
WIRE 16 -1 (-6500 1600)(-6500 1375);
WIRE 16 -1 (-6825 1600)(-6500 1600);
WIRE 16 -1 (-6825 1500)(-6825 1600);
WIRE 16 -1 (-7550 1500)(-6825 1500);
FORCEPROP 2 LAST SIG_NAME VSENSE_PVCCIN_CPU0_N
J 0
(-7560 1510);
DISPLAY 0.617021 (-7560 1510);
PAINT ORANGE (-7560 1510);
WIRE 16 -1 (-5375 1825)(-4325 1825);
FORCEPROP 2 LAST SIG_NAME VSENSE_PVCCIN_CPU0_SKT_VSEN
J 0
(-5198 1844);
DISPLAY 0.617021 (-5198 1844);
PAINT ORANGE (-5198 1844);
WIRE 16 -1 (-5350 1375)(-4325 1375);
FORCEPROP 2 LAST SIG_NAME VSENSE_PVCCIN_CPU0_SKT_VRTN
J 0
(-5135 1385);
DISPLAY 0.617021 (-5135 1385);
PAINT ORANGE (-5135 1385);
DOT 1 (-7025 3875);
DOT 1 (-3850 3725);
DOT 1 (-700 3625);
DOT 1 (-5200 3875);
DOT 1 (-5200 4750);
DOT 1 (-4875 4750);
DOT 1 (-575 2175);
DOT 1 (-2475 3475);
DOT 1 (-400 3625);
DOT 1 (-4675 4750);
DOT 1 (-3725 4425);
DOT 1 (-2475 3375);
DOT 1 (-2475 3425);
DOT 1 (-1975 3625);
DOT 1 (-2075 4125);
DOT 1 (-875 3625);
DOT 1 (-6275 1825);
DOT 1 (-6275 1375);
DOT 1 (-6675 4425);
DOT 1 (-3725 4275);
DOT 1 (-5850 1375);
DOT 1 (-5850 1825);
DOT 1 (-5700 3875);
DOT 1 (-5700 4475);
DOT 1 (-6000 4425);
DOT 1 (-6000 3875);
DOT 1 (-6300 3875);
DOT 1 (-6600 4425);
DOT 1 (-6600 3875);
DOT 1 (-6900 4425);
DOT 1 (-6900 3875);
DOT 1 (-6300 4425);
DOT 1 (-400 3050);
DOT 1 (-1975 3350);
DOT 1 (-925 2175);
DOT 1 (-1175 1700);
DOT 1 (-1400 2175);
DOT 1 (-925 1700);
FORCENOTE
KELVIN
(-1940 2540) 0;
DISPLAY LEFT (-1940 2540);
PAINT PURPLE (-1940 2540);
FORCENOTE
ROOM=PVCCIN_CPU0_PWR_VR
(-5505 2510) 0;
DISPLAY LEFT (-5505 2510);
DISPLAY 2.446809 (-5505 2510);
PAINT PURPLE (-5505 2510);
FORCENOTE
VR CONTROLLER SIDE
(-7915 1615) 0;
DISPLAY LEFT (-7915 1615);
PAINT PURPLE (-7915 1615);
FORCENOTE
LL=0.9MOHM
(-7825 1950) 0;
DISPLAY LEFT (-7825 1950);
DISPLAY 0.808511 (-7825 1950);
PAINT PURPLE (-7825 1950);
FORCENOTE
VBOOT=1.7V
(-7825 1900) 0;
DISPLAY LEFT (-7825 1900);
DISPLAY 0.808511 (-7825 1900);
PAINT PURPLE (-7825 1900);
FORCENOTE
TP FAB1 ADD NET NAME 12/04
(-3125 3075) 0;
DISPLAY LEFT (-3125 3075);
DISPLAY 1.021277 (-3125 3075);
PAINT RED (-3125 3075);
FORCENOTE
TP FAB1 DELETE ADM4073, CAP, RES 0321
(-1550 775) 0;
DISPLAY LEFT (-1550 775);
DISPLAY 1.021277 (-1550 775);
PAINT RED (-1550 775);
FORCENOTE
ROOM = PVCCIN_CPU0_FILTER_VR
(-3665 565) 0;
DISPLAY LEFT (-3665 565);
DISPLAY 2.446809 (-3665 565);
PAINT PURPLE (-3665 565);
FORCENOTE
TDA21470
(-3300 4550) 0;
DISPLAY LEFT (-3300 4550);
DISPLAY 1.021277 (-3300 4550);
PAINT SKYBLUE (-3300 4550);
FORCENOTE
INPUT CURRENT SENSE FOR VCCIN AND VSA
(-1940 2615) 0;
DISPLAY LEFT (-1940 2615);
PAINT PURPLE (-1940 2615);
FORCENOTE
TP FAB1 CHANGE RES PN 0218
(-1525 2200) 0;
DISPLAY LEFT (-1525 2200);
DISPLAY 0.808511 (-1525 2200);
PAINT RED (-1525 2200);
FORCENOTE
TP FAB1 CO-LAY WITH TI PARTS 11/16
(-1650 3825) 0;
DISPLAY LEFT (-1650 3825);
DISPLAY 0.851064 (-1650 3825);
PAINT RED (-1650 3825);
FORCENOTE
TP FAB1 CHANGE PN 0310
(-5375 4375) 0;
DISPLAY LEFT (-5375 4375);
DISPLAY 1.021277 (-5375 4375);
PAINT RED (-5375 4375);
FORCENOTE
TP FAB1 CHANGE TO 0 OHM 0107
(-5725 4850) 0;
DISPLAY LEFT (-5725 4850);
DISPLAY 0.638298 (-5725 4850);
PAINT RED (-5725 4850);
FORCENOTE
TP FAB1 CHANGE L4C1 PN 0122
(-3500 1850) 0;
DISPLAY LEFT (-3500 1850);
DISPLAY 1.021277 (-3500 1850);
PAINT RED (-3500 1850);
FORCENOTE
TP FAB1 CO-LAY WITH TI PARTS 11/16
(-5175 3300) 0;
DISPLAY LEFT (-5175 3300);
DISPLAY 0.851064 (-5175 3300);
PAINT RED (-5175 3300);
FORCENOTE
ROOM = PVCCIN_CPU0_VSENSE_VR
(-7165 515) 0;
DISPLAY LEFT (-7165 515);
DISPLAY 2.446809 (-7165 515);
PAINT PURPLE (-7165 515);
FORCENOTE
VOUT=1.8V(NOM)
(-7825 2400) 0;
DISPLAY LEFT (-7825 2400);
DISPLAY 0.808511 (-7825 2400);
PAINT PURPLE (-7825 2400);
FORCENOTE
RIPPLE GUIDE= +/- 5MV
(-7825 2350) 0;
DISPLAY LEFT (-7825 2350);
DISPLAY 0.808511 (-7825 2350);
PAINT PURPLE (-7825 2350);
FORCENOTE
DC TOL = +/-17MV
(-7825 2300) 0;
DISPLAY LEFT (-7825 2300);
DISPLAY 0.808511 (-7825 2300);
PAINT PURPLE (-7825 2300);
FORCENOTE
AC + RIPPLE TOL =  +/-22MV
(-7825 2250) 0;
DISPLAY LEFT (-7825 2250);
DISPLAY 0.808511 (-7825 2250);
PAINT PURPLE (-7825 2250);
FORCENOTE
IOUT TDC=88A
(-7825 2200) 0;
DISPLAY LEFT (-7825 2200);
DISPLAY 0.808511 (-7825 2200);
PAINT PURPLE (-7825 2200);
FORCENOTE
IOUT PK=228A
(-7825 2150) 0;
DISPLAY LEFT (-7825 2150);
DISPLAY 0.808511 (-7825 2150);
PAINT PURPLE (-7825 2150);
FORCENOTE
IOUT DI/DT = 778 A/US
(-7825 2050) 0;
DISPLAY LEFT (-7825 2050);
DISPLAY 0.808511 (-7825 2050);
PAINT PURPLE (-7825 2050);
FORCENOTE
SW FREQ=625 KHZ 
(-7825 2000) 0;
DISPLAY LEFT (-7825 2000);
DISPLAY 0.808511 (-7825 2000);
PAINT PURPLE (-7825 2000);
FORCENOTE
IOUT STEP=187 APP
(-7825 2100) 0;
DISPLAY LEFT (-7825 2100);
DISPLAY 0.808511 (-7825 2100);
PAINT PURPLE (-7825 2100);
FORCENOTE
ROUT AS DIFF PAIR
(-6890 1615) 0;
DISPLAY LEFT (-6890 1615);
DISPLAY 0.808511 (-6890 1615);
PAINT PURPLE (-6890 1615);
FORCENOTE
10MIL WIDTH
(-6765 1540) 0;
DISPLAY LEFT (-6765 1540);
DISPLAY 0.808511 (-6765 1540);
PAINT PURPLE (-6765 1540);
FORCENOTE
5MIL SPACING
(-6790 1465) 0;
DISPLAY LEFT (-6790 1465);
DISPLAY 0.808511 (-6790 1465);
PAINT PURPLE (-6790 1465);
FORCENOTE
PVCCIN CPU0 VOLTAGE SENSE
(-7351 1228) 0;
DISPLAY LEFT (-7351 1228);
PAINT PURPLE (-7351 1228);
FORCENOTE
SOCKET SIDE
(-4790 1615) 0;
DISPLAY LEFT (-4790 1615);
PAINT PURPLE (-4790 1615);
FORCENOTE
TP FAB1 DEL NET 0309
(-2425 4225) 0;
DISPLAY LEFT (-2425 4225);
DISPLAY 1.021277 (-2425 4225);
PAINT RED (-2425 4225);
FORCENOTE
CONNECTION
(-1940 2465) 0;
DISPLAY LEFT (-1940 2465);
PAINT PURPLE (-1940 2465);
FORCENOTE
TP FAB1 CHANGE RES TO 1 OHM 0603 0107
(-2025 2750) 0;
DISPLAY LEFT (-2025 2750);
DISPLAY 1.021277 (-2025 2750);
PAINT RED (-2025 2750);
FORCENOTE
TP FAB1 CO-LAY WITH TI PARTS 11/16
(-1975 2850) 0;
DISPLAY LEFT (-1975 2850);
DISPLAY 0.851064 (-1975 2850);
PAINT RED (-1975 2850);
FORCENOTE
SPOF
(-5855 3175) 0;
DISPLAY LEFT (-5855 3175);
DISPLAY 1.936170 (-5855 3175);
PAINT PURPLE (-5855 3175);
FORCENOTE
TP FAB1 CHANGE L4C3 PN 0122
(-1375 3775) 0;
DISPLAY LEFT (-1375 3775);
DISPLAY 1.021277 (-1375 3775);
PAINT RED (-1375 3775);
FORCENOTE
INPUT FILTER
(-2940 2340) 0;
DISPLAY LEFT (-2940 2340);
PAINT PURPLE (-2940 2340);
FORCENOTE
PLACE ON TOP
(-5380 3900) 0;
DISPLAY LEFT (-5380 3900);
DISPLAY 1.553191 (-5380 3900);
PAINT PURPLE (-5380 3900);
QUIT
